FILE_TYPE = MACRO_DRAWING;
SET COLOR_WIRE YELLOW;
SET COLOR_PROP ORANGE;
SET COLOR_DOT WHITE;
SET COLOR_ARC YELLOW;
SET COLOR_BODY GREEN;
SET COLOR_NOTE PURPLE;
SET PROP_DISPLAY VALUE;
SET PAGE_NUMBER P301;
FORCEADD UNIVERSAL_GND..1
(-2650 -2400);
FORCEPROP 3 LASTPIN (-2650 -2350) SIG_NAME AGND_HSC\g
J 0
(-2640 -2340);
DISPLAY 0.659574 (-2640 -2340);
PAINT MONO (-2640 -2340);
DISPLAY INVISIBLE (-2640 -2340);
FORCEPROP 1 LAST HDL_POWER AGND_HSC
J 1
(-2625 -2475);
DISPLAY 0.723404 (-2625 -2475);
PAINT GREEN (-2625 -2475);
FORCEPROP 2 LAST CDS_LIB pure_quanta_power
J 0
(-2650 -2400);
DISPLAY INVISIBLE (-2650 -2400);
FORCEPROP 1 LAST PATH I1
J 0
(-2575 -2400);
DISPLAY 0.872340 (-2575 -2400);
PAINT AQUA (-2575 -2400);
DISPLAY INVISIBLE (-2575 -2400);
FORCEADD OFFPAGE..4
R 2
(-2050 -1425);
FORCEPROP 2 LAST $XR2 265 
J 0
(-2542 -1425);
DISPLAY 0.638298 (-2542 -1425);
PAINT MONO (-2542 -1425);
FORCEPROP 2 LAST $XR1 264 
J 0
(-2422 -1425);
DISPLAY 0.638298 (-2422 -1425);
PAINT MONO (-2422 -1425);
FORCEPROP 2 LAST $XR0 263 
J 0
(-2302 -1425);
DISPLAY 0.638298 (-2302 -1425);
PAINT MONO (-2302 -1425);
FORCEPROP 2 LAST CDS_LIB standard
J 0
(-2050 -1425);
DISPLAY INVISIBLE (-2050 -1425);
FORCEPROP 1 LAST OFFPAGE TRUE
J 2
(-2375 -1550);
DISPLAY 0.872340 (-2375 -1550);
PAINT GREEN (-2375 -1550);
DISPLAY INVISIBLE (-2375 -1550);
FORCEPROP 1 LAST COMMENT_BODY TRUE
J 2
(-2025 -1525);
DISPLAY 0.872340 (-2025 -1525);
PAINT GREEN (-2025 -1525);
DISPLAY INVISIBLE (-2025 -1525);
FORCEPROP 2 LAST PATH I10
J 0
(-2300 -1375);
DISPLAY 1.021277 (-2300 -1375);
DISPLAY INVISIBLE (-2300 -1375);
FORCEADD Q_RES..1
(-1925 -1250);
FORCEPROP 1 LAST LOCATION PR3912
J 0
(-2250 -1225);
DISPLAY 0.723404 (-2250 -1225);
PAINT AQUA (-2250 -1225);
FORCEPROP 0 LAST $SEC 1
J 0
(-1875 -1175);
DISPLAY 0.680851 (-1875 -1175);
PAINT MONO (-1875 -1175);
DISPLAY INVISIBLE (-1875 -1175);
FORCEPROP 0 LAST CDS_SEC 1
J 0
(-1875 -1175);
DISPLAY 1.021277 (-1875 -1175);
DISPLAY INVISIBLE (-1875 -1175);
FORCEPROP 1 LASTPIN (-2025 -1250) $PN 1
J 0
(-2013 -1238);
DISPLAY 0.787234 (-2013 -1238);
PAINT MONO (-2013 -1238);
FORCEPROP 1 LASTPIN (-1825 -1250) $PN 2
J 0
(-1863 -1238);
DISPLAY 0.787234 (-1863 -1238);
PAINT MONO (-1863 -1238);
FORCEPROP 0 LAST ROOM HSC BOM1
J 0
(-2350 -1300);
DISPLAY 0.553191 (-2350 -1300);
FORCEPROP 1 LAST VALUE 120K
J 2
(-1950 -1325);
DISPLAY 0.723404 (-1950 -1325);
PAINT SKYBLUE (-1950 -1325);
FORCEPROP 1 LAST MATERIAL CHIP
J 0
(-1875 -1375);
DISPLAY 0.723404 (-1875 -1375);
PAINT SKYBLUE (-1875 -1375);
FORCEPROP 1 LAST PACK_TYPE 0402LF
J 0
(-1800 -1325);
DISPLAY 0.723404 (-1800 -1325);
PAINT SKYBLUE (-1800 -1325);
FORCEPROP 1 LAST WATTAGE 1/16W
J 2
(-1900 -1375);
DISPLAY 0.723404 (-1900 -1375);
PAINT SKYBLUE (-1900 -1375);
FORCEPROP 1 LAST TOLERANCE 1%
J 0
(-1900 -1325);
DISPLAY 0.723404 (-1900 -1325);
PAINT SKYBLUE (-1900 -1325);
FORCEPROP 2 LAST CDS_LIB pure_quanta
J 0
(-1925 -1250);
DISPLAY INVISIBLE (-1925 -1250);
FORCEPROP 1 LAST PATH I11
J 0
(-1975 -1100);
DISPLAY 0.978723 (-1975 -1100);
PAINT WHITE (-1975 -1100);
DISPLAY INVISIBLE (-1975 -1100);
FORCEPROP 1 LAST PART_NUMBER CS41202FB05
J 0
(-1775 -1225);
DISPLAY 0.723404 (-1775 -1225);
PAINT WHITE (-1775 -1225);
DISPLAY INVISIBLE (-1775 -1225);
FORCEADD Q_CAP..1
(-1975 -2075);
FORCEPROP 1 LAST LOCATION PC2348
J 0
(-1900 -1975);
DISPLAY 0.638298 (-1900 -1975);
PAINT AQUA (-1900 -1975);
FORCEPROP 0 LAST $SEC 1
J 0
(-1900 -1925);
DISPLAY 0.680851 (-1900 -1925);
PAINT MONO (-1900 -1925);
DISPLAY INVISIBLE (-1900 -1925);
FORCEPROP 0 LAST CDS_SEC 1
J 0
(-1900 -1925);
DISPLAY 1.021277 (-1900 -1925);
DISPLAY INVISIBLE (-1900 -1925);
FORCEPROP 1 LASTPIN (-1975 -1975) $PN 1
J 0
(-1965 -1995);
DISPLAY 0.787234 (-1965 -1995);
PAINT MONO (-1965 -1995);
FORCEPROP 1 LASTPIN (-1975 -2175) $PN 2
J 0
(-1965 -2195);
DISPLAY 0.787234 (-1965 -2195);
PAINT MONO (-1965 -2195);
FORCEPROP 1 LAST MATERIAL EMPTY
J 0
(-1900 -2125);
DISPLAY 0.723404 (-1900 -2125);
PAINT RED (-1900 -2125);
FORCEPROP 1 LAST VALUE 1NF
J 0
(-1900 -2025);
DISPLAY 0.723404 (-1900 -2025);
PAINT SKYBLUE (-1900 -2025);
FORCEPROP 1 LAST PACK_TYPE 0402
J 0
(-1900 -2225);
DISPLAY 0.723404 (-1900 -2225);
PAINT SKYBLUE (-1900 -2225);
FORCEPROP 0 LAST ROOM HSC BOM1
J 0
(-1900 -1925);
DISPLAY 0.680851 (-1900 -1925);
FORCEPROP 1 LAST VOLTAGE 50V
J 0
(-1900 -2075);
DISPLAY 0.723404 (-1900 -2075);
PAINT SKYBLUE (-1900 -2075);
FORCEPROP 1 LAST TOLERANCE 10%
J 0
(-1925 -2125);
DISPLAY 0.978723 (-1925 -2125);
PAINT SKYBLUE (-1925 -2125);
DISPLAY INVISIBLE (-1925 -2125);
FORCEPROP 2 LAST CDS_LIB pure_quanta
J 0
(-1975 -2075);
DISPLAY INVISIBLE (-1975 -2075);
FORCEPROP 1 LAST PATH I12
J 0
(-1925 -1925);
DISPLAY 0.978723 (-1925 -1925);
PAINT WHITE (-1925 -1925);
DISPLAY INVISIBLE (-1925 -1925);
FORCEPROP 1 LAST PART_NUMBER CH21006KB16
J 0
(-1900 -2175);
DISPLAY 0.723404 (-1900 -2175);
PAINT WHITE (-1900 -2175);
DISPLAY INVISIBLE (-1900 -2175);
FORCEADD Q_RES..2
(-1500 -2075);
FORCEPROP 1 LAST LOCATION PR3915
J 0
(-1445 -1925);
DISPLAY 0.723404 (-1445 -1925);
PAINT AQUA (-1445 -1925);
FORCEPROP 0 LAST $SEC 1
J 0
(-1425 -1875);
DISPLAY 0.680851 (-1425 -1875);
PAINT MONO (-1425 -1875);
DISPLAY INVISIBLE (-1425 -1875);
FORCEPROP 0 LAST CDS_SEC 1
J 0
(-1425 -1875);
DISPLAY 1.021277 (-1425 -1875);
DISPLAY INVISIBLE (-1425 -1875);
FORCEPROP 1 LASTPIN (-1500 -1975) $PN 1
J 0
(-1495 -2013);
DISPLAY 0.787234 (-1495 -2013);
PAINT MONO (-1495 -2013);
FORCEPROP 1 LASTPIN (-1500 -2175) $PN 2
J 0
(-1495 -2165);
DISPLAY 0.787234 (-1495 -2165);
PAINT MONO (-1495 -2165);
FORCEPROP 1 LAST VALUE 2K
J 0
(-1445 -1975);
DISPLAY 0.723404 (-1445 -1975);
PAINT SKYBLUE (-1445 -1975);
FORCEPROP 1 LAST TOLERANCE 0.1%
J 0
(-1445 -2025);
DISPLAY 0.723404 (-1445 -2025);
PAINT SKYBLUE (-1445 -2025);
FORCEPROP 1 LAST PACK_TYPE 0402LF
J 0
(-1450 -2225);
DISPLAY 0.723404 (-1450 -2225);
PAINT SKYBLUE (-1450 -2225);
FORCEPROP 0 LAST ROOM HSC BOM1
J 0
(-1475 -2300);
DISPLAY 0.680851 (-1475 -2300);
FORCEPROP 1 LAST MATERIAL CHIP
J 0
(-1450 -2125);
DISPLAY 0.723404 (-1450 -2125);
PAINT SKYBLUE (-1450 -2125);
FORCEPROP 1 LAST WATTAGE 1/16W
J 0
(-1450 -2075);
DISPLAY 0.723404 (-1450 -2075);
PAINT SKYBLUE (-1450 -2075);
FORCEPROP 2 LAST CDS_LIB pure_quanta
J 0
(-1500 -2075);
DISPLAY INVISIBLE (-1500 -2075);
FORCEPROP 1 LAST PATH I13
J 0
(-1450 -1900);
DISPLAY 0.978723 (-1450 -1900);
PAINT WHITE (-1450 -1900);
DISPLAY INVISIBLE (-1450 -1900);
FORCEPROP 1 LAST PART_NUMBER CS22002BB07
J 0
(-1450 -2175);
DISPLAY 0.723404 (-1450 -2175);
PAINT WHITE (-1450 -2175);
DISPLAY INVISIBLE (-1450 -2175);
FORCEADD OFFPAGE..5
(-1075 -1850);
FORCEPROP 2 LAST $XR2 263 
J 0
(-1330 -1814);
DISPLAY 0.638298 (-1330 -1814);
PAINT MONO (-1330 -1814);
FORCEPROP 2 LAST $XR1 265 
J 0
(-1450 -1850);
DISPLAY 0.638298 (-1450 -1850);
PAINT MONO (-1450 -1850);
FORCEPROP 2 LAST $XR0 264 
J 0
(-1330 -1850);
DISPLAY 0.638298 (-1330 -1850);
PAINT MONO (-1330 -1850);
FORCEPROP 2 LAST CDS_LIB standard
J 0
(-1075 -1850);
DISPLAY INVISIBLE (-1075 -1850);
FORCEPROP 1 LAST OFFPAGE TRUE
J 0
(-750 -1975);
DISPLAY 0.872340 (-750 -1975);
PAINT AQUA (-750 -1975);
DISPLAY INVISIBLE (-750 -1975);
FORCEPROP 1 LAST COMMENT_BODY TRUE
J 0
(-975 -1925);
DISPLAY 1.170213 (-975 -1925);
PAINT GREEN (-975 -1925);
DISPLAY INVISIBLE (-975 -1925);
FORCEPROP 2 LAST PATH I14
J 0
(-1325 -1775);
DISPLAY 1.021277 (-1325 -1775);
DISPLAY INVISIBLE (-1325 -1775);
FORCEADD Q_RES..2
(-975 -2075);
FORCEPROP 1 LAST LOCATION PR1101
J 0
(-920 -1925);
DISPLAY 0.723404 (-920 -1925);
PAINT AQUA (-920 -1925);
FORCEPROP 0 LAST $SEC 1
J 0
(-900 -1875);
DISPLAY 0.680851 (-900 -1875);
PAINT MONO (-900 -1875);
DISPLAY INVISIBLE (-900 -1875);
FORCEPROP 0 LAST CDS_SEC 1
J 0
(-900 -1875);
DISPLAY 1.021277 (-900 -1875);
DISPLAY INVISIBLE (-900 -1875);
FORCEPROP 1 LASTPIN (-975 -1975) $PN 1
J 0
(-970 -2013);
DISPLAY 0.787234 (-970 -2013);
PAINT MONO (-970 -2013);
FORCEPROP 1 LASTPIN (-975 -2175) $PN 2
J 0
(-970 -2165);
DISPLAY 0.787234 (-970 -2165);
PAINT MONO (-970 -2165);
FORCEPROP 1 LAST TOLERANCE 0.1%
J 0
(-920 -2025);
DISPLAY 0.723404 (-920 -2025);
PAINT SKYBLUE (-920 -2025);
FORCEPROP 1 LAST VALUE 2K
J 0
(-920 -1975);
DISPLAY 0.723404 (-920 -1975);
PAINT SKYBLUE (-920 -1975);
FORCEPROP 0 LAST ROOM HSC BOM1
J 0
(-925 -2300);
DISPLAY 0.680851 (-925 -2300);
FORCEPROP 1 LAST PACK_TYPE 0402LF
J 0
(-925 -2225);
DISPLAY 0.723404 (-925 -2225);
PAINT SKYBLUE (-925 -2225);
FORCEPROP 1 LAST MATERIAL CHIP
J 0
(-925 -2125);
DISPLAY 0.723404 (-925 -2125);
PAINT SKYBLUE (-925 -2125);
FORCEPROP 1 LAST WATTAGE 1/16W
J 0
(-925 -2075);
DISPLAY 0.723404 (-925 -2075);
PAINT SKYBLUE (-925 -2075);
FORCEPROP 2 LAST CDS_LIB pure_quanta
J 0
(-975 -2075);
DISPLAY INVISIBLE (-975 -2075);
FORCEPROP 1 LAST PATH I15
J 0
(-925 -1900);
DISPLAY 0.978723 (-925 -1900);
PAINT WHITE (-925 -1900);
DISPLAY INVISIBLE (-925 -1900);
FORCEPROP 1 LAST PART_NUMBER CS22002BB07
J 0
(-925 -2175);
DISPLAY 0.723404 (-925 -2175);
PAINT WHITE (-925 -2175);
DISPLAY INVISIBLE (-925 -2175);
FORCEADD MP5991GLUZ..1
(0 -1325);
FORCEPROP 1 LAST LOCATION PU288
J 0
(-320 -244);
DISPLAY 0.723404 (-320 -244);
PAINT GREEN (-320 -244);
FORCEPROP 2 LAST SEC 1
J 0
(-300 -100);
DISPLAY 0.680851 (-300 -100);
PAINT MONO (-300 -100);
DISPLAY INVISIBLE (-300 -100);
FORCEPROP 2 LASTPIN (-475 -1750) $PN 23
J 2
(-485 -1740);
DISPLAY 0.680851 (-485 -1740);
PAINT MONO (-485 -1740);
FORCEPROP 2 LASTPIN (475 -1400) $PN 3
J 0
(485 -1390);
DISPLAY 0.680851 (485 -1390);
PAINT MONO (485 -1390);
FORCEPROP 2 LASTPIN (475 -1500) $PN 6
J 0
(485 -1490);
DISPLAY 0.680851 (485 -1490);
PAINT MONO (485 -1490);
FORCEPROP 2 LASTPIN (-475 -2050) $PN 20
J 2
(-485 -2040);
DISPLAY 0.680851 (-485 -2040);
PAINT MONO (-485 -2040);
FORCEPROP 2 LASTPIN (475 -1700) $PN 5
J 0
(485 -1690);
DISPLAY 0.680851 (485 -1690);
PAINT MONO (485 -1690);
FORCEPROP 2 LASTPIN (-475 -1850) $PN 22
J 2
(-485 -1840);
DISPLAY 0.680851 (-485 -1840);
PAINT MONO (-485 -1840);
FORCEPROP 2 LASTPIN (-475 -1250) $PN 8
J 2
(-485 -1240);
DISPLAY 0.680851 (-485 -1240);
PAINT MONO (-485 -1240);
FORCEPROP 2 LASTPIN (475 -1600) $PN 7
J 0
(485 -1590);
DISPLAY 0.680851 (485 -1590);
PAINT MONO (485 -1590);
FORCEPROP 2 LASTPIN (-475 -1650) $PN 24
J 2
(-485 -1640);
DISPLAY 0.680851 (-485 -1640);
PAINT MONO (-485 -1640);
FORCEPROP 2 LASTPIN (-475 -1550) $PN 4
J 2
(-485 -1540);
DISPLAY 0.680851 (-485 -1540);
PAINT MONO (-485 -1540);
FORCEPROP 2 LASTPIN (-475 -1350) $PN 17
J 2
(-485 -1340);
DISPLAY 0.680851 (-485 -1340);
PAINT MONO (-485 -1340);
FORCEPROP 2 LASTPIN (475 -1900) $PN 19
J 0
(485 -1890);
DISPLAY 0.680851 (485 -1890);
PAINT MONO (485 -1890);
FORCEPROP 2 LASTPIN (-475 -1150) $PN 21
J 2
(-485 -1140);
DISPLAY 0.680851 (-485 -1140);
PAINT MONO (-485 -1140);
FORCEPROP 2 LASTPIN (-475 -600) $PN 9
J 2
(-485 -590);
DISPLAY 0.680851 (-485 -590);
PAINT MONO (-485 -590);
FORCEPROP 2 LASTPIN (-475 -650) $PN 10
J 2
(-485 -640);
DISPLAY 0.680851 (-485 -640);
PAINT MONO (-485 -640);
FORCEPROP 2 LASTPIN (-475 -700) $PN 11
J 2
(-485 -690);
DISPLAY 0.680851 (-485 -690);
PAINT MONO (-485 -690);
FORCEPROP 2 LASTPIN (-475 -750) $PN 12
J 2
(-485 -740);
DISPLAY 0.680851 (-485 -740);
PAINT MONO (-485 -740);
FORCEPROP 2 LASTPIN (-475 -800) $PN 13
J 2
(-485 -790);
DISPLAY 0.680851 (-485 -790);
PAINT MONO (-485 -790);
FORCEPROP 2 LASTPIN (-475 -850) $PN 14
J 2
(-485 -840);
DISPLAY 0.680851 (-485 -840);
PAINT MONO (-485 -840);
FORCEPROP 2 LASTPIN (-475 -900) $PN 15
J 2
(-485 -890);
DISPLAY 0.680851 (-485 -890);
PAINT MONO (-485 -890);
FORCEPROP 2 LASTPIN (-475 -950) $PN 16
J 2
(-485 -940);
DISPLAY 0.680851 (-485 -940);
PAINT MONO (-485 -940);
FORCEPROP 2 LASTPIN (-475 -1000) $PN 33
J 2
(-485 -990);
DISPLAY 0.680851 (-485 -990);
PAINT MONO (-485 -990);
FORCEPROP 2 LASTPIN (475 -600) $PN 1
J 0
(485 -590);
DISPLAY 0.680851 (485 -590);
PAINT MONO (485 -590);
FORCEPROP 2 LASTPIN (475 -650) $PN 2
J 0
(485 -640);
DISPLAY 0.680851 (485 -640);
PAINT MONO (485 -640);
FORCEPROP 2 LASTPIN (475 -700) $PN 25
J 0
(485 -690);
DISPLAY 0.680851 (485 -690);
PAINT MONO (485 -690);
FORCEPROP 2 LASTPIN (475 -750) $PN 26
J 0
(485 -740);
DISPLAY 0.680851 (485 -740);
PAINT MONO (485 -740);
FORCEPROP 2 LASTPIN (475 -800) $PN 27
J 0
(485 -790);
DISPLAY 0.680851 (485 -790);
PAINT MONO (485 -790);
FORCEPROP 2 LASTPIN (475 -850) $PN 28
J 0
(485 -840);
DISPLAY 0.680851 (485 -840);
PAINT MONO (485 -840);
FORCEPROP 2 LASTPIN (475 -900) $PN 29
J 0
(485 -890);
DISPLAY 0.680851 (485 -890);
PAINT MONO (485 -890);
FORCEPROP 2 LASTPIN (475 -950) $PN 30
J 0
(485 -940);
DISPLAY 0.680851 (485 -940);
PAINT MONO (485 -940);
FORCEPROP 2 LASTPIN (475 -1000) $PN 31
J 0
(485 -990);
DISPLAY 0.680851 (485 -990);
PAINT MONO (485 -990);
FORCEPROP 2 LASTPIN (475 -1050) $PN 32
J 0
(485 -1040);
DISPLAY 0.680851 (485 -1040);
PAINT MONO (485 -1040);
FORCEPROP 2 LASTPIN (475 -1800) $PN 18
J 0
(485 -1790);
DISPLAY 0.680851 (485 -1790);
PAINT MONO (485 -1790);
FORCEPROP 1 LAST MATERIAL IC
J 0
(-320 -518);
DISPLAY 0.723404 (-320 -518);
PAINT GREEN (-320 -518);
FORCEPROP 2 LAST PART_TYPE SMLF
J 0
(-300 -150);
DISPLAY 1.021277 (-300 -150);
FORCEPROP 0 LAST ROOM HSC BOM1
J 0
(-300 -50);
DISPLAY 0.680851 (-300 -50);
FORCEPROP 2 LAST VALUE MP5991GLU-Z
J 0
(-300 -200);
DISPLAY 1.021277 (-300 -200);
FORCEPROP 1 LAST NEEDS_NO_SIZE TRUE
J 0
(0 -1325);
DISPLAY 0.723404 (0 -1325);
PAINT GREEN (0 -1325);
DISPLAY INVISIBLE (0 -1325);
FORCEPROP 1 LAST CDS_LMAN_SYM_OUTLINE -325,775,325,-775
J 0
(0 -1325);
DISPLAY 0.468085 (0 -1325);
PAINT GREEN (0 -1325);
DISPLAY INVISIBLE (0 -1325);
FORCEPROP 2 LAST CDS_LIB pure_quanta
J 0
(0 -1325);
DISPLAY INVISIBLE (0 -1325);
FORCEPROP 2 LAST SEC_TYPE 
J 0
(-300 -100);
DISPLAY 1.021277 (-300 -100);
DISPLAY INVISIBLE (-300 -100);
FORCEPROP 1 LAST PATH I16
J 0
(0 -1325);
DISPLAY 0.723404 (0 -1325);
PAINT GREEN (0 -1325);
DISPLAY INVISIBLE (0 -1325);
FORCEPROP 1 LAST PART_NUMBER AL005991A00
J 0
(-320 -391);
DISPLAY 0.723404 (-320 -391);
PAINT GREEN (-320 -391);
DISPLAY INVISIBLE (-320 -391);
FORCEADD Q_RES..1
(-1325 -1425);
FORCEPROP 1 LAST LOCATION PR3917
J 0
(-1625 -1425);
DISPLAY 0.723404 (-1625 -1425);
PAINT AQUA (-1625 -1425);
FORCEPROP 0 LAST $SEC 1
J 0
(-1200 -1350);
DISPLAY 0.680851 (-1200 -1350);
PAINT MONO (-1200 -1350);
DISPLAY INVISIBLE (-1200 -1350);
FORCEPROP 0 LAST CDS_SEC 1
J 0
(-1200 -1350);
DISPLAY 1.021277 (-1200 -1350);
DISPLAY INVISIBLE (-1200 -1350);
FORCEPROP 1 LASTPIN (-1425 -1425) $PN 1
J 0
(-1413 -1413);
DISPLAY 0.787234 (-1413 -1413);
PAINT MONO (-1413 -1413);
FORCEPROP 1 LASTPIN (-1225 -1425) $PN 2
J 0
(-1263 -1413);
DISPLAY 0.787234 (-1263 -1413);
PAINT MONO (-1263 -1413);
FORCEPROP 1 LAST WATTAGE 1/16W
J 2
(-1450 -1525);
DISPLAY 0.723404 (-1450 -1525);
PAINT SKYBLUE (-1450 -1525);
FORCEPROP 1 LAST PACK_TYPE 0402LF
J 0
(-1400 -1525);
DISPLAY 0.723404 (-1400 -1525);
PAINT SKYBLUE (-1400 -1525);
FORCEPROP 1 LAST VALUE 0
J 2
(-1150 -1400);
DISPLAY 0.723404 (-1150 -1400);
PAINT SKYBLUE (-1150 -1400);
FORCEPROP 1 LAST TOLERANCE 5%
J 0
(-1200 -1475);
DISPLAY 0.723404 (-1200 -1475);
PAINT SKYBLUE (-1200 -1475);
FORCEPROP 1 LAST MATERIAL CHIP
J 0
(-1150 -1525);
DISPLAY 0.723404 (-1150 -1525);
PAINT SKYBLUE (-1150 -1525);
FORCEPROP 0 LAST ROOM HSC BOM1
J 0
(-1425 -1350);
DISPLAY 0.553191 (-1425 -1350);
FORCEPROP 2 LAST CDS_LIB pure_quanta
J 0
(-1325 -1425);
DISPLAY INVISIBLE (-1325 -1425);
FORCEPROP 1 LAST PATH I17
J 0
(-1375 -1275);
DISPLAY 0.978723 (-1375 -1275);
PAINT WHITE (-1375 -1275);
DISPLAY INVISIBLE (-1375 -1275);
FORCEPROP 1 LAST PART_NUMBER CS00002JB13
J 0
(-1650 -1475);
DISPLAY 0.723404 (-1650 -1475);
PAINT WHITE (-1650 -1475);
DISPLAY INVISIBLE (-1650 -1475);
FORCEADD UNIVERSAL_POWER..1
(-975 -450);
FORCEPROP 3 LASTPIN (-975 -500) SIG_NAME P12V_PSU\g
J 0
(-965 -490);
DISPLAY 0.659574 (-965 -490);
PAINT MONO (-965 -490);
DISPLAY INVISIBLE (-965 -490);
FORCEPROP 1 LAST HDL_POWER P12V_PSU
J 1
(-975 -400);
DISPLAY 0.723404 (-975 -400);
PAINT GREEN (-975 -400);
FORCEPROP 2 LAST BOM_COST MIO_VRD_SB
J 0
(-975 -350);
DISPLAY 0.617021 (-975 -350);
PAINT PURPLE (-975 -350);
DISPLAY INVISIBLE (-975 -350);
FORCEPROP 2 LAST CDS_LIB pure_quanta_power
J 0
(-975 -450);
DISPLAY INVISIBLE (-975 -450);
FORCEPROP 1 LAST PATH I18
J 0
(-925 -425);
DISPLAY 0.872340 (-925 -425);
PAINT AQUA (-925 -425);
DISPLAY INVISIBLE (-925 -425);
FORCEADD UNIVERSAL_GND..1
(-3450 1075);
FORCEPROP 3 LASTPIN (-3450 1125) SIG_NAME AGND_HSC\g
J 0
(-3440 1135);
DISPLAY 0.659574 (-3440 1135);
PAINT MONO (-3440 1135);
DISPLAY INVISIBLE (-3440 1135);
FORCEPROP 1 LAST HDL_POWER AGND_HSC
J 1
(-3425 1000);
DISPLAY 0.723404 (-3425 1000);
PAINT GREEN (-3425 1000);
FORCEPROP 2 LAST CDS_LIB pure_quanta_power
J 0
(-3450 1075);
DISPLAY INVISIBLE (-3450 1075);
FORCEPROP 1 LAST PATH I19
J 0
(-3375 1075);
DISPLAY 0.872340 (-3375 1075);
PAINT AQUA (-3375 1075);
DISPLAY INVISIBLE (-3375 1075);
FORCEADD Q_CAP..1
(-2650 -2075);
FORCEPROP 1 LAST LOCATION PC2183
J 0
(-2575 -1975);
DISPLAY 0.723404 (-2575 -1975);
PAINT AQUA (-2575 -1975);
FORCEPROP 0 LAST $SEC 1
J 0
(-2575 -1925);
DISPLAY 0.680851 (-2575 -1925);
PAINT MONO (-2575 -1925);
DISPLAY INVISIBLE (-2575 -1925);
FORCEPROP 0 LAST CDS_SEC 1
J 0
(-2575 -1925);
DISPLAY 1.021277 (-2575 -1925);
DISPLAY INVISIBLE (-2575 -1925);
FORCEPROP 1 LASTPIN (-2650 -1975) $PN 1
J 0
(-2640 -1995);
DISPLAY 0.787234 (-2640 -1995);
PAINT MONO (-2640 -1995);
FORCEPROP 1 LASTPIN (-2650 -2175) $PN 2
J 0
(-2640 -2195);
DISPLAY 0.787234 (-2640 -2195);
PAINT MONO (-2640 -2195);
FORCEPROP 1 LAST VALUE 220PF
J 0
(-2575 -2025);
DISPLAY 0.723404 (-2575 -2025);
PAINT SKYBLUE (-2575 -2025);
FORCEPROP 1 LAST VOLTAGE 50V
J 0
(-2575 -2075);
DISPLAY 0.723404 (-2575 -2075);
PAINT SKYBLUE (-2575 -2075);
FORCEPROP 1 LAST PACK_TYPE 0402
J 0
(-2575 -2225);
DISPLAY 0.723404 (-2575 -2225);
PAINT SKYBLUE (-2575 -2225);
FORCEPROP 1 LAST MATERIAL EMPTY
J 0
(-2575 -2125);
DISPLAY 0.723404 (-2575 -2125);
PAINT RED (-2575 -2125);
FORCEPROP 0 LAST ROOM HSC BOM1
J 0
(-2575 -1925);
DISPLAY 0.702128 (-2575 -1925);
FORCEPROP 2 LAST CDS_LIB pure_quanta
J 0
(-2650 -2075);
DISPLAY INVISIBLE (-2650 -2075);
FORCEPROP 1 LAST TOLERANCE 10%
J 0
(-2600 -2125);
DISPLAY 0.978723 (-2600 -2125);
PAINT SKYBLUE (-2600 -2125);
DISPLAY INVISIBLE (-2600 -2125);
FORCEPROP 1 LAST PATH I2
J 0
(-2600 -1925);
DISPLAY 0.978723 (-2600 -1925);
PAINT WHITE (-2600 -1925);
DISPLAY INVISIBLE (-2600 -1925);
FORCEPROP 1 LAST PART_NUMBER TMP_QCH12206KB14
J 0
(-2575 -2175);
DISPLAY 0.723404 (-2575 -2175);
PAINT WHITE (-2575 -2175);
DISPLAY INVISIBLE (-2575 -2175);
FORCEADD Q_CAP..1
(-3450 1375);
FORCEPROP 1 LAST LOCATION PC1525
J 0
(-3375 1525);
DISPLAY 0.723404 (-3375 1525);
PAINT AQUA (-3375 1525);
FORCEPROP 0 LAST $SEC 1
J 0
(-3375 1575);
DISPLAY 0.680851 (-3375 1575);
PAINT MONO (-3375 1575);
DISPLAY INVISIBLE (-3375 1575);
FORCEPROP 0 LAST CDS_SEC 1
J 0
(-3375 1575);
DISPLAY 1.021277 (-3375 1575);
DISPLAY INVISIBLE (-3375 1575);
FORCEPROP 1 LASTPIN (-3450 1475) $PN 1
J 0
(-3440 1455);
DISPLAY 0.787234 (-3440 1455);
PAINT MONO (-3440 1455);
FORCEPROP 1 LASTPIN (-3450 1275) $PN 2
J 0
(-3440 1255);
DISPLAY 0.787234 (-3440 1255);
PAINT MONO (-3440 1255);
FORCEPROP 1 LAST MATERIAL X6S
J 0
(-3375 1375);
DISPLAY 0.723404 (-3375 1375);
PAINT SKYBLUE (-3375 1375);
FORCEPROP 1 LAST VOLTAGE 25V
J 0
(-3375 1425);
DISPLAY 0.723404 (-3375 1425);
PAINT SKYBLUE (-3375 1425);
FORCEPROP 1 LAST PACK_TYPE C0402
J 0
(-3375 1275);
DISPLAY 0.723404 (-3375 1275);
PAINT SKYBLUE (-3375 1275);
FORCEPROP 1 LAST VALUE 1UF
J 0
(-3375 1475);
DISPLAY 0.723404 (-3375 1475);
PAINT SKYBLUE (-3375 1475);
FORCEPROP 0 LAST ROOM HSC BOM1
J 0
(-3375 1575);
DISPLAY 0.680851 (-3375 1575);
FORCEPROP 2 LAST CDS_LIB pure_quanta
J 0
(-3450 1375);
DISPLAY INVISIBLE (-3450 1375);
FORCEPROP 1 LAST TOLERANCE 10%
J 0
(-3400 1325);
DISPLAY 0.978723 (-3400 1325);
PAINT SKYBLUE (-3400 1325);
DISPLAY INVISIBLE (-3400 1325);
FORCEPROP 1 LAST PATH I20
J 0
(-3400 1525);
DISPLAY 0.978723 (-3400 1525);
PAINT WHITE (-3400 1525);
DISPLAY INVISIBLE (-3400 1525);
FORCEPROP 1 LAST PART_NUMBER CH5104KEB02
J 0
(-3375 1325);
DISPLAY 0.723404 (-3375 1325);
PAINT WHITE (-3375 1325);
DISPLAY INVISIBLE (-3375 1325);
FORCEADD Q_RES..1
R 1
(-3450 1850);
FORCEPROP 1 LAST LOCATION PR3910
J 0
(-3375 2000);
DISPLAY 0.723404 (-3375 2000);
PAINT AQUA (-3375 2000);
FORCEPROP 0 LAST $SEC 1
R 1
J 0
(-3375 2050);
DISPLAY 0.680851 (-3375 2050);
PAINT MONO (-3375 2050);
DISPLAY INVISIBLE (-3375 2050);
FORCEPROP 0 LAST CDS_SEC 1
R 1
J 0
(-3375 2050);
DISPLAY 1.021277 (-3375 2050);
DISPLAY INVISIBLE (-3375 2050);
FORCEPROP 1 LASTPIN (-3450 1750) $PN 1
R 1
J 0
(-3462 1762);
DISPLAY 0.787234 (-3462 1762);
PAINT MONO (-3462 1762);
FORCEPROP 1 LASTPIN (-3450 1950) $PN 2
R 1
J 0
(-3462 1912);
DISPLAY 0.787234 (-3462 1912);
PAINT MONO (-3462 1912);
FORCEPROP 1 LAST WATTAGE 1/16W
J 0
(-3375 1800);
DISPLAY 0.723404 (-3375 1800);
PAINT SKYBLUE (-3375 1800);
FORCEPROP 1 LAST MATERIAL CHIP
J 0
(-3375 1850);
DISPLAY 0.787234 (-3375 1850);
PAINT SKYBLUE (-3375 1850);
FORCEPROP 1 LAST TOLERANCE 5%
J 0
(-3375 1900);
DISPLAY 0.723404 (-3375 1900);
PAINT SKYBLUE (-3375 1900);
FORCEPROP 1 LAST VALUE 0
R 2
J 0
(-3350 1975);
DISPLAY 0.723404 (-3350 1975);
PAINT SKYBLUE (-3350 1975);
FORCEPROP 1 LAST PACK_TYPE 0402LF
J 0
(-3375 1700);
DISPLAY 0.723404 (-3375 1700);
PAINT SKYBLUE (-3375 1700);
FORCEPROP 0 LAST ROOM HSC BOM1
J 0
(-3375 2050);
DISPLAY 0.680851 (-3375 2050);
FORCEPROP 2 LAST CDS_LIB pure_quanta
J 0
(-3450 1850);
DISPLAY INVISIBLE (-3450 1850);
FORCEPROP 1 LAST PATH I21
R 1
J 0
(-3600 1800);
DISPLAY 0.978723 (-3600 1800);
PAINT WHITE (-3600 1800);
DISPLAY INVISIBLE (-3600 1800);
FORCEPROP 1 LAST PART_NUMBER CS00002JB13
J 0
(-3375 1750);
DISPLAY 0.723404 (-3375 1750);
PAINT WHITE (-3375 1750);
DISPLAY INVISIBLE (-3375 1750);
FORCEADD UNIVERSAL_POWER..1
(-3450 2100);
FORCEPROP 3 LASTPIN (-3450 2050) SIG_NAME HSC_VDD\g
J 0
(-3440 2060);
DISPLAY 0.659574 (-3440 2060);
PAINT MONO (-3440 2060);
DISPLAY INVISIBLE (-3440 2060);
FORCEPROP 1 LAST HDL_POWER HSC_VDD
J 1
(-3450 2150);
DISPLAY 0.723404 (-3450 2150);
PAINT GREEN (-3450 2150);
FORCEPROP 2 LAST CDS_LIB pure_quanta_power
J 0
(-3450 2100);
DISPLAY INVISIBLE (-3450 2100);
FORCEPROP 2 LAST BOM_COST MIO_VRD_SB
J 0
(-3450 2200);
DISPLAY 0.617021 (-3450 2200);
PAINT PURPLE (-3450 2200);
DISPLAY INVISIBLE (-3450 2200);
FORCEPROP 1 LAST PATH I22
J 0
(-3400 2125);
DISPLAY 0.872340 (-3400 2125);
PAINT AQUA (-3400 2125);
DISPLAY INVISIBLE (-3400 2125);
FORCEADD UNIVERSAL_GND..1
(-2675 425);
FORCEPROP 3 LASTPIN (-2675 475) SIG_NAME AGND_HSC\g
J 0
(-2665 485);
DISPLAY 0.659574 (-2665 485);
PAINT MONO (-2665 485);
DISPLAY INVISIBLE (-2665 485);
FORCEPROP 1 LAST HDL_POWER AGND_HSC
J 1
(-2650 350);
DISPLAY 0.723404 (-2650 350);
PAINT GREEN (-2650 350);
FORCEPROP 2 LAST CDS_LIB pure_quanta_power
J 0
(-2675 425);
DISPLAY INVISIBLE (-2675 425);
FORCEPROP 1 LAST PATH I23
J 0
(-2600 425);
DISPLAY 0.872340 (-2600 425);
PAINT AQUA (-2600 425);
DISPLAY INVISIBLE (-2600 425);
FORCEADD Q_CAP..1
(-2675 725);
FORCEPROP 1 LAST LOCATION PC2182
J 0
(-2600 825);
DISPLAY 0.723404 (-2600 825);
PAINT AQUA (-2600 825);
FORCEPROP 0 LAST $SEC 1
J 0
(-2600 875);
DISPLAY 0.680851 (-2600 875);
PAINT MONO (-2600 875);
DISPLAY INVISIBLE (-2600 875);
FORCEPROP 0 LAST CDS_SEC 1
J 0
(-2600 875);
DISPLAY 1.021277 (-2600 875);
DISPLAY INVISIBLE (-2600 875);
FORCEPROP 1 LASTPIN (-2675 825) $PN 1
J 0
(-2665 805);
DISPLAY 0.787234 (-2665 805);
PAINT MONO (-2665 805);
FORCEPROP 1 LASTPIN (-2675 625) $PN 2
J 0
(-2665 605);
DISPLAY 0.787234 (-2665 605);
PAINT MONO (-2665 605);
FORCEPROP 1 LAST VALUE 220PF
J 0
(-2600 775);
DISPLAY 0.723404 (-2600 775);
PAINT SKYBLUE (-2600 775);
FORCEPROP 1 LAST VOLTAGE 50V
J 0
(-2600 725);
DISPLAY 0.723404 (-2600 725);
PAINT SKYBLUE (-2600 725);
FORCEPROP 1 LAST MATERIAL X7R
J 0
(-2600 675);
DISPLAY 0.723404 (-2600 675);
PAINT SKYBLUE (-2600 675);
FORCEPROP 1 LAST PACK_TYPE 0402
J 0
(-2600 575);
DISPLAY 0.723404 (-2600 575);
PAINT SKYBLUE (-2600 575);
FORCEPROP 0 LAST ROOM HSC BOM1
J 0
(-2600 875);
DISPLAY 0.680851 (-2600 875);
FORCEPROP 1 LAST TOLERANCE 10%
J 0
(-2625 675);
DISPLAY 0.978723 (-2625 675);
PAINT SKYBLUE (-2625 675);
DISPLAY INVISIBLE (-2625 675);
FORCEPROP 2 LAST CDS_LIB pure_quanta
J 0
(-2675 725);
DISPLAY INVISIBLE (-2675 725);
FORCEPROP 1 LAST PATH I24
J 0
(-2625 875);
DISPLAY 0.978723 (-2625 875);
PAINT WHITE (-2625 875);
DISPLAY INVISIBLE (-2625 875);
FORCEPROP 1 LAST PART_NUMBER TMP_QCH12206KB14
J 0
(-2600 625);
DISPLAY 0.723404 (-2600 625);
PAINT WHITE (-2600 625);
DISPLAY INVISIBLE (-2600 625);
FORCEADD OFFPAGE..4
R 2
(-2150 1150);
FORCEPROP 2 LAST $XR2 265 
J 0
(-2642 1150);
DISPLAY 0.638298 (-2642 1150);
PAINT MONO (-2642 1150);
FORCEPROP 2 LAST $XR0 263 
J 0
(-2402 1150);
DISPLAY 0.638298 (-2402 1150);
PAINT MONO (-2402 1150);
FORCEPROP 2 LAST $XR1 264 
J 0
(-2522 1150);
DISPLAY 0.638298 (-2522 1150);
PAINT MONO (-2522 1150);
FORCEPROP 2 LAST CDS_LIB standard
J 0
(-2150 1150);
DISPLAY INVISIBLE (-2150 1150);
FORCEPROP 1 LAST OFFPAGE TRUE
J 2
(-2475 1025);
DISPLAY 0.872340 (-2475 1025);
PAINT GREEN (-2475 1025);
DISPLAY INVISIBLE (-2475 1025);
FORCEPROP 1 LAST COMMENT_BODY TRUE
J 2
(-2125 1050);
DISPLAY 0.872340 (-2125 1050);
PAINT GREEN (-2125 1050);
DISPLAY INVISIBLE (-2125 1050);
FORCEPROP 2 LAST PATH I25
J 0
(-2400 1200);
DISPLAY 1.021277 (-2400 1200);
DISPLAY INVISIBLE (-2400 1200);
FORCEADD OFFPAGE..4
R 2
(-2775 1250);
FORCEPROP 2 LAST $XR2 265 
J 0
(-3057 1214);
DISPLAY 0.638298 (-3057 1214);
PAINT MONO (-3057 1214);
FORCEPROP 2 LAST $XR1 264 
J 0
(-3177 1250);
DISPLAY 0.638298 (-3177 1250);
PAINT MONO (-3177 1250);
FORCEPROP 2 LAST $XR0 263 
J 0
(-3057 1250);
DISPLAY 0.638298 (-3057 1250);
PAINT MONO (-3057 1250);
FORCEPROP 2 LAST CDS_LIB standard
J 0
(-2775 1250);
DISPLAY INVISIBLE (-2775 1250);
FORCEPROP 1 LAST OFFPAGE TRUE
J 2
(-3100 1125);
DISPLAY 0.872340 (-3100 1125);
PAINT GREEN (-3100 1125);
DISPLAY INVISIBLE (-3100 1125);
FORCEPROP 1 LAST COMMENT_BODY TRUE
J 2
(-2750 1150);
DISPLAY 0.872340 (-2750 1150);
PAINT GREEN (-2750 1150);
DISPLAY INVISIBLE (-2750 1150);
FORCEPROP 2 LAST PATH I26
J 0
(-3050 1300);
DISPLAY 1.021277 (-3050 1300);
DISPLAY INVISIBLE (-3050 1300);
FORCEADD UNIVERSAL_GND..1
(-2625 1475);
FORCEPROP 3 LASTPIN (-2625 1525) SIG_NAME AGND_HSC\g
J 0
(-2615 1535);
DISPLAY 0.659574 (-2615 1535);
PAINT MONO (-2615 1535);
DISPLAY INVISIBLE (-2615 1535);
FORCEPROP 1 LAST HDL_POWER AGND_HSC
J 1
(-2600 1400);
DISPLAY 0.723404 (-2600 1400);
PAINT GREEN (-2600 1400);
FORCEPROP 2 LAST CDS_LIB pure_quanta_power
J 0
(-2625 1475);
DISPLAY INVISIBLE (-2625 1475);
FORCEPROP 1 LAST PATH I27
J 0
(-2550 1475);
DISPLAY 0.872340 (-2550 1475);
PAINT AQUA (-2550 1475);
DISPLAY INVISIBLE (-2550 1475);
FORCEADD OFFPAGE..4
R 2
(-2050 1375);
FORCEPROP 2 LAST $XR2 265 
J 0
(-2542 1375);
DISPLAY 0.638298 (-2542 1375);
PAINT MONO (-2542 1375);
FORCEPROP 2 LAST $XR1 264 
J 0
(-2422 1375);
DISPLAY 0.638298 (-2422 1375);
PAINT MONO (-2422 1375);
FORCEPROP 2 LAST $XR0 263 
J 0
(-2302 1375);
DISPLAY 0.638298 (-2302 1375);
PAINT MONO (-2302 1375);
FORCEPROP 2 LAST CDS_LIB standard
J 0
(-2050 1375);
DISPLAY INVISIBLE (-2050 1375);
FORCEPROP 1 LAST OFFPAGE TRUE
J 2
(-2375 1250);
DISPLAY 0.872340 (-2375 1250);
PAINT GREEN (-2375 1250);
DISPLAY INVISIBLE (-2375 1250);
FORCEPROP 1 LAST COMMENT_BODY TRUE
J 2
(-2025 1275);
DISPLAY 0.872340 (-2025 1275);
PAINT GREEN (-2025 1275);
DISPLAY INVISIBLE (-2025 1275);
FORCEPROP 2 LAST PATH I28
J 0
(-2300 1425);
DISPLAY 1.021277 (-2300 1425);
DISPLAY INVISIBLE (-2300 1425);
FORCEADD Q_RES..1
(-1925 1550);
FORCEPROP 1 LAST LOCATION PR1134
J 0
(-2200 1575);
DISPLAY 0.723404 (-2200 1575);
PAINT AQUA (-2200 1575);
FORCEPROP 0 LAST $SEC 1
J 0
(-1875 1625);
DISPLAY 0.680851 (-1875 1625);
PAINT MONO (-1875 1625);
DISPLAY INVISIBLE (-1875 1625);
FORCEPROP 0 LAST CDS_SEC 1
J 0
(-1875 1625);
DISPLAY 1.021277 (-1875 1625);
DISPLAY INVISIBLE (-1875 1625);
FORCEPROP 1 LASTPIN (-2025 1550) $PN 1
J 0
(-2013 1562);
DISPLAY 0.787234 (-2013 1562);
PAINT MONO (-2013 1562);
FORCEPROP 1 LASTPIN (-1825 1550) $PN 2
J 0
(-1863 1562);
DISPLAY 0.787234 (-1863 1562);
PAINT MONO (-1863 1562);
FORCEPROP 1 LAST MATERIAL CHIP
J 0
(-1875 1425);
DISPLAY 0.723404 (-1875 1425);
PAINT SKYBLUE (-1875 1425);
FORCEPROP 1 LAST VALUE 120K
J 2
(-1950 1475);
DISPLAY 0.723404 (-1950 1475);
PAINT SKYBLUE (-1950 1475);
FORCEPROP 1 LAST PACK_TYPE 0402LF
J 0
(-1800 1475);
DISPLAY 0.723404 (-1800 1475);
PAINT SKYBLUE (-1800 1475);
FORCEPROP 1 LAST TOLERANCE 1%
J 0
(-1900 1475);
DISPLAY 0.723404 (-1900 1475);
PAINT SKYBLUE (-1900 1475);
FORCEPROP 0 LAST ROOM HSC BOM1
J 0
(-2350 1500);
DISPLAY 0.680851 (-2350 1500);
FORCEPROP 1 LAST WATTAGE 1/16W
J 2
(-1900 1425);
DISPLAY 0.723404 (-1900 1425);
PAINT SKYBLUE (-1900 1425);
FORCEPROP 2 LAST CDS_LIB pure_quanta
J 0
(-1925 1550);
DISPLAY INVISIBLE (-1925 1550);
FORCEPROP 1 LAST PATH I29
J 0
(-1975 1700);
DISPLAY 0.978723 (-1975 1700);
PAINT WHITE (-1975 1700);
DISPLAY INVISIBLE (-1975 1700);
FORCEPROP 1 LAST PART_NUMBER CS41202FB05
J 0
(-1775 1575);
DISPLAY 0.723404 (-1775 1575);
PAINT WHITE (-1775 1575);
DISPLAY INVISIBLE (-1775 1575);
FORCEADD UNIVERSAL_GND..1
(-3475 -1725);
FORCEPROP 3 LASTPIN (-3475 -1675) SIG_NAME AGND_HSC\g
J 0
(-3465 -1665);
DISPLAY 0.659574 (-3465 -1665);
PAINT MONO (-3465 -1665);
DISPLAY INVISIBLE (-3465 -1665);
FORCEPROP 1 LAST HDL_POWER AGND_HSC
J 1
(-3450 -1800);
DISPLAY 0.723404 (-3450 -1800);
PAINT GREEN (-3450 -1800);
FORCEPROP 2 LAST CDS_LIB pure_quanta_power
J 0
(-3475 -1725);
DISPLAY INVISIBLE (-3475 -1725);
FORCEPROP 1 LAST PATH I3
J 0
(-3400 -1725);
DISPLAY 0.872340 (-3400 -1725);
PAINT AQUA (-3400 -1725);
DISPLAY INVISIBLE (-3400 -1725);
FORCEADD Q_CAP..1
(-2000 725);
FORCEPROP 1 LAST LOCATION PC2347
J 0
(-1925 825);
DISPLAY 0.723404 (-1925 825);
PAINT AQUA (-1925 825);
FORCEPROP 0 LAST $SEC 1
J 0
(-1925 875);
DISPLAY 0.680851 (-1925 875);
PAINT MONO (-1925 875);
DISPLAY INVISIBLE (-1925 875);
FORCEPROP 0 LAST CDS_SEC 1
J 0
(-1925 875);
DISPLAY 1.021277 (-1925 875);
DISPLAY INVISIBLE (-1925 875);
FORCEPROP 1 LASTPIN (-2000 825) $PN 1
J 0
(-1990 805);
DISPLAY 0.787234 (-1990 805);
PAINT MONO (-1990 805);
FORCEPROP 1 LASTPIN (-2000 625) $PN 2
J 0
(-1990 605);
DISPLAY 0.787234 (-1990 605);
PAINT MONO (-1990 605);
FORCEPROP 1 LAST PACK_TYPE 0402
J 0
(-1925 575);
DISPLAY 0.723404 (-1925 575);
PAINT SKYBLUE (-1925 575);
FORCEPROP 1 LAST VALUE 1NF
J 0
(-1925 775);
DISPLAY 0.723404 (-1925 775);
PAINT SKYBLUE (-1925 775);
FORCEPROP 1 LAST VOLTAGE 50V
J 0
(-1925 725);
DISPLAY 0.723404 (-1925 725);
PAINT SKYBLUE (-1925 725);
FORCEPROP 1 LAST MATERIAL EMPTY
J 0
(-1925 675);
DISPLAY 0.723404 (-1925 675);
PAINT RED (-1925 675);
FORCEPROP 0 LAST ROOM HSC BOM1
J 0
(-1925 875);
DISPLAY 0.680851 (-1925 875);
FORCEPROP 1 LAST TOLERANCE 10%
J 0
(-1950 675);
DISPLAY 0.978723 (-1950 675);
PAINT SKYBLUE (-1950 675);
DISPLAY INVISIBLE (-1950 675);
FORCEPROP 2 LAST CDS_LIB pure_quanta
J 0
(-2000 725);
DISPLAY INVISIBLE (-2000 725);
FORCEPROP 1 LAST PATH I30
J 0
(-1950 875);
DISPLAY 0.978723 (-1950 875);
PAINT WHITE (-1950 875);
DISPLAY INVISIBLE (-1950 875);
FORCEPROP 1 LAST PART_NUMBER CH21006KB16
J 0
(-1925 625);
DISPLAY 0.723404 (-1925 625);
PAINT WHITE (-1925 625);
DISPLAY INVISIBLE (-1925 625);
FORCEADD Q_RES..2
(-1500 725);
FORCEPROP 1 LAST LOCATION PR3914
J 0
(-1445 875);
DISPLAY 0.723404 (-1445 875);
PAINT AQUA (-1445 875);
FORCEPROP 0 LAST $SEC 1
J 0
(-1425 925);
DISPLAY 0.680851 (-1425 925);
PAINT MONO (-1425 925);
DISPLAY INVISIBLE (-1425 925);
FORCEPROP 0 LAST CDS_SEC 1
J 0
(-1425 925);
DISPLAY 1.021277 (-1425 925);
DISPLAY INVISIBLE (-1425 925);
FORCEPROP 1 LASTPIN (-1500 825) $PN 1
J 0
(-1495 787);
DISPLAY 0.787234 (-1495 787);
PAINT MONO (-1495 787);
FORCEPROP 1 LASTPIN (-1500 625) $PN 2
J 0
(-1495 635);
DISPLAY 0.787234 (-1495 635);
PAINT MONO (-1495 635);
FORCEPROP 1 LAST MATERIAL CHIP
J 0
(-1450 675);
DISPLAY 0.723404 (-1450 675);
PAINT SKYBLUE (-1450 675);
FORCEPROP 1 LAST WATTAGE 1/16W
J 0
(-1450 725);
DISPLAY 0.723404 (-1450 725);
PAINT SKYBLUE (-1450 725);
FORCEPROP 1 LAST TOLERANCE 0.1%
J 0
(-1445 775);
DISPLAY 0.723404 (-1445 775);
PAINT SKYBLUE (-1445 775);
FORCEPROP 1 LAST VALUE 2K
J 0
(-1445 825);
DISPLAY 0.723404 (-1445 825);
PAINT SKYBLUE (-1445 825);
FORCEPROP 1 LAST PACK_TYPE 0402LF
J 0
(-1450 575);
DISPLAY 0.723404 (-1450 575);
PAINT SKYBLUE (-1450 575);
FORCEPROP 0 LAST ROOM HSC BOM1
J 0
(-1275 675);
DISPLAY 0.553191 (-1275 675);
FORCEPROP 2 LAST CDS_LIB pure_quanta
J 0
(-1500 725);
DISPLAY INVISIBLE (-1500 725);
FORCEPROP 1 LAST PATH I31
J 0
(-1450 900);
DISPLAY 0.978723 (-1450 900);
PAINT WHITE (-1450 900);
DISPLAY INVISIBLE (-1450 900);
FORCEPROP 1 LAST PART_NUMBER CS22002BB07
J 0
(-1450 625);
DISPLAY 0.723404 (-1450 625);
PAINT WHITE (-1450 625);
DISPLAY INVISIBLE (-1450 625);
FORCEADD OFFPAGE..5
(-1075 950);
FORCEPROP 2 LAST $XR2 263 
J 0
(-1330 986);
DISPLAY 0.638298 (-1330 986);
PAINT MONO (-1330 986);
FORCEPROP 2 LAST $XR1 265 
J 0
(-1450 950);
DISPLAY 0.638298 (-1450 950);
PAINT MONO (-1450 950);
FORCEPROP 2 LAST $XR0 264 
J 0
(-1330 950);
DISPLAY 0.638298 (-1330 950);
PAINT MONO (-1330 950);
FORCEPROP 2 LAST CDS_LIB standard
J 0
(-1075 950);
DISPLAY INVISIBLE (-1075 950);
FORCEPROP 1 LAST OFFPAGE TRUE
J 0
(-750 825);
DISPLAY 0.872340 (-750 825);
PAINT AQUA (-750 825);
DISPLAY INVISIBLE (-750 825);
FORCEPROP 1 LAST COMMENT_BODY TRUE
J 0
(-975 875);
DISPLAY 1.170213 (-975 875);
PAINT GREEN (-975 875);
DISPLAY INVISIBLE (-975 875);
FORCEPROP 2 LAST PATH I32
J 0
(-1325 1025);
DISPLAY 1.021277 (-1325 1025);
DISPLAY INVISIBLE (-1325 1025);
FORCEADD Q_RES..1
(-1350 1375);
FORCEPROP 1 LAST LOCATION PR3916
J 0
(-1650 1375);
DISPLAY 0.723404 (-1650 1375);
PAINT AQUA (-1650 1375);
FORCEPROP 0 LAST $SEC 1
J 0
(-1225 1450);
DISPLAY 0.680851 (-1225 1450);
PAINT MONO (-1225 1450);
DISPLAY INVISIBLE (-1225 1450);
FORCEPROP 0 LAST CDS_SEC 1
J 0
(-1225 1450);
DISPLAY 1.021277 (-1225 1450);
DISPLAY INVISIBLE (-1225 1450);
FORCEPROP 1 LASTPIN (-1450 1375) $PN 1
J 0
(-1438 1387);
DISPLAY 0.787234 (-1438 1387);
PAINT MONO (-1438 1387);
FORCEPROP 1 LASTPIN (-1250 1375) $PN 2
J 0
(-1288 1387);
DISPLAY 0.787234 (-1288 1387);
PAINT MONO (-1288 1387);
FORCEPROP 1 LAST PACK_TYPE 0402LF
J 0
(-1425 1275);
DISPLAY 0.723404 (-1425 1275);
PAINT SKYBLUE (-1425 1275);
FORCEPROP 1 LAST WATTAGE 1/16W
J 2
(-1475 1275);
DISPLAY 0.723404 (-1475 1275);
PAINT SKYBLUE (-1475 1275);
FORCEPROP 1 LAST VALUE 0
J 2
(-1200 1400);
DISPLAY 0.723404 (-1200 1400);
PAINT SKYBLUE (-1200 1400);
FORCEPROP 0 LAST ROOM HSC BOM1
J 0
(-1450 1450);
DISPLAY 0.553191 (-1450 1450);
FORCEPROP 1 LAST MATERIAL CHIP
J 0
(-1175 1275);
DISPLAY 0.723404 (-1175 1275);
PAINT SKYBLUE (-1175 1275);
FORCEPROP 1 LAST TOLERANCE 5%
J 0
(-1225 1325);
DISPLAY 0.723404 (-1225 1325);
PAINT SKYBLUE (-1225 1325);
FORCEPROP 2 LAST CDS_LIB pure_quanta
J 0
(-1350 1375);
DISPLAY INVISIBLE (-1350 1375);
FORCEPROP 1 LAST PATH I33
J 0
(-1400 1525);
DISPLAY 0.978723 (-1400 1525);
PAINT WHITE (-1400 1525);
DISPLAY INVISIBLE (-1400 1525);
FORCEPROP 1 LAST PART_NUMBER CS00002JB13
J 0
(-1675 1325);
DISPLAY 0.723404 (-1675 1325);
PAINT WHITE (-1675 1325);
DISPLAY INVISIBLE (-1675 1325);
FORCEADD Q_RES..2
(-975 725);
FORCEPROP 1 LAST LOCATION PR3918
J 0
(-920 875);
DISPLAY 0.723404 (-920 875);
PAINT AQUA (-920 875);
FORCEPROP 0 LAST $SEC 1
J 0
(-900 925);
DISPLAY 0.680851 (-900 925);
PAINT MONO (-900 925);
DISPLAY INVISIBLE (-900 925);
FORCEPROP 0 LAST CDS_SEC 1
J 0
(-900 925);
DISPLAY 1.021277 (-900 925);
DISPLAY INVISIBLE (-900 925);
FORCEPROP 1 LASTPIN (-975 825) $PN 1
J 0
(-970 787);
DISPLAY 0.787234 (-970 787);
PAINT MONO (-970 787);
FORCEPROP 1 LASTPIN (-975 625) $PN 2
J 0
(-970 635);
DISPLAY 0.787234 (-970 635);
PAINT MONO (-970 635);
FORCEPROP 0 LAST ROOM HSC BOM1
J 0
(-750 675);
DISPLAY 0.553191 (-750 675);
FORCEPROP 1 LAST MATERIAL CHIP
J 0
(-925 675);
DISPLAY 0.723404 (-925 675);
PAINT SKYBLUE (-925 675);
FORCEPROP 1 LAST WATTAGE 1/16W
J 0
(-925 725);
DISPLAY 0.723404 (-925 725);
PAINT SKYBLUE (-925 725);
FORCEPROP 1 LAST TOLERANCE 0.1%
J 0
(-920 775);
DISPLAY 0.723404 (-920 775);
PAINT SKYBLUE (-920 775);
FORCEPROP 1 LAST VALUE 2K
J 0
(-920 825);
DISPLAY 0.723404 (-920 825);
PAINT SKYBLUE (-920 825);
FORCEPROP 1 LAST PACK_TYPE 0402LF
J 0
(-925 575);
DISPLAY 0.723404 (-925 575);
PAINT SKYBLUE (-925 575);
FORCEPROP 2 LAST CDS_LIB pure_quanta
J 0
(-975 725);
DISPLAY INVISIBLE (-975 725);
FORCEPROP 1 LAST PATH I34
J 0
(-925 900);
DISPLAY 0.978723 (-925 900);
PAINT WHITE (-925 900);
DISPLAY INVISIBLE (-925 900);
FORCEPROP 1 LAST PART_NUMBER CS22002BB07
J 0
(-925 625);
DISPLAY 0.723404 (-925 625);
PAINT WHITE (-925 625);
DISPLAY INVISIBLE (-925 625);
FORCEADD MP5991GLUZ..1
(0 1475);
FORCEPROP 1 LAST LOCATION PU287
J 0
(-320 2556);
DISPLAY 0.723404 (-320 2556);
PAINT GREEN (-320 2556);
FORCEPROP 2 LAST SEC 1
J 0
(-300 2700);
DISPLAY 0.680851 (-300 2700);
PAINT MONO (-300 2700);
DISPLAY INVISIBLE (-300 2700);
FORCEPROP 2 LASTPIN (-475 1050) $PN 23
J 2
(-485 1060);
DISPLAY 0.680851 (-485 1060);
PAINT MONO (-485 1060);
FORCEPROP 2 LASTPIN (475 1400) $PN 3
J 0
(485 1410);
DISPLAY 0.680851 (485 1410);
PAINT MONO (485 1410);
FORCEPROP 2 LASTPIN (475 1300) $PN 6
J 0
(485 1310);
DISPLAY 0.680851 (485 1310);
PAINT MONO (485 1310);
FORCEPROP 2 LASTPIN (-475 750) $PN 20
J 2
(-485 760);
DISPLAY 0.680851 (-485 760);
PAINT MONO (-485 760);
FORCEPROP 2 LASTPIN (475 1100) $PN 5
J 0
(485 1110);
DISPLAY 0.680851 (485 1110);
PAINT MONO (485 1110);
FORCEPROP 2 LASTPIN (-475 950) $PN 22
J 2
(-485 960);
DISPLAY 0.680851 (-485 960);
PAINT MONO (-485 960);
FORCEPROP 2 LASTPIN (-475 1550) $PN 8
J 2
(-485 1560);
DISPLAY 0.680851 (-485 1560);
PAINT MONO (-485 1560);
FORCEPROP 2 LASTPIN (475 1200) $PN 7
J 0
(485 1210);
DISPLAY 0.680851 (485 1210);
PAINT MONO (485 1210);
FORCEPROP 2 LASTPIN (-475 1150) $PN 24
J 2
(-485 1160);
DISPLAY 0.680851 (-485 1160);
PAINT MONO (-485 1160);
FORCEPROP 2 LASTPIN (-475 1250) $PN 4
J 2
(-485 1260);
DISPLAY 0.680851 (-485 1260);
PAINT MONO (-485 1260);
FORCEPROP 2 LASTPIN (-475 1450) $PN 17
J 2
(-485 1460);
DISPLAY 0.680851 (-485 1460);
PAINT MONO (-485 1460);
FORCEPROP 2 LASTPIN (475 900) $PN 19
J 0
(485 910);
DISPLAY 0.680851 (485 910);
PAINT MONO (485 910);
FORCEPROP 2 LASTPIN (-475 1650) $PN 21
J 2
(-485 1660);
DISPLAY 0.680851 (-485 1660);
PAINT MONO (-485 1660);
FORCEPROP 2 LASTPIN (-475 2200) $PN 9
J 2
(-485 2210);
DISPLAY 0.680851 (-485 2210);
PAINT MONO (-485 2210);
FORCEPROP 2 LASTPIN (-475 2150) $PN 10
J 2
(-485 2160);
DISPLAY 0.680851 (-485 2160);
PAINT MONO (-485 2160);
FORCEPROP 2 LASTPIN (-475 2100) $PN 11
J 2
(-485 2110);
DISPLAY 0.680851 (-485 2110);
PAINT MONO (-485 2110);
FORCEPROP 2 LASTPIN (-475 2050) $PN 12
J 2
(-485 2060);
DISPLAY 0.680851 (-485 2060);
PAINT MONO (-485 2060);
FORCEPROP 2 LASTPIN (-475 2000) $PN 13
J 2
(-485 2010);
DISPLAY 0.680851 (-485 2010);
PAINT MONO (-485 2010);
FORCEPROP 2 LASTPIN (-475 1950) $PN 14
J 2
(-485 1960);
DISPLAY 0.680851 (-485 1960);
PAINT MONO (-485 1960);
FORCEPROP 2 LASTPIN (-475 1900) $PN 15
J 2
(-485 1910);
DISPLAY 0.680851 (-485 1910);
PAINT MONO (-485 1910);
FORCEPROP 2 LASTPIN (-475 1850) $PN 16
J 2
(-485 1860);
DISPLAY 0.680851 (-485 1860);
PAINT MONO (-485 1860);
FORCEPROP 2 LASTPIN (-475 1800) $PN 33
J 2
(-485 1810);
DISPLAY 0.680851 (-485 1810);
PAINT MONO (-485 1810);
FORCEPROP 2 LASTPIN (475 2200) $PN 1
J 0
(485 2210);
DISPLAY 0.680851 (485 2210);
PAINT MONO (485 2210);
FORCEPROP 2 LASTPIN (475 2150) $PN 2
J 0
(485 2160);
DISPLAY 0.680851 (485 2160);
PAINT MONO (485 2160);
FORCEPROP 2 LASTPIN (475 2100) $PN 25
J 0
(485 2110);
DISPLAY 0.680851 (485 2110);
PAINT MONO (485 2110);
FORCEPROP 2 LASTPIN (475 2050) $PN 26
J 0
(485 2060);
DISPLAY 0.680851 (485 2060);
PAINT MONO (485 2060);
FORCEPROP 2 LASTPIN (475 2000) $PN 27
J 0
(485 2010);
DISPLAY 0.680851 (485 2010);
PAINT MONO (485 2010);
FORCEPROP 2 LASTPIN (475 1950) $PN 28
J 0
(485 1960);
DISPLAY 0.680851 (485 1960);
PAINT MONO (485 1960);
FORCEPROP 2 LASTPIN (475 1900) $PN 29
J 0
(485 1910);
DISPLAY 0.680851 (485 1910);
PAINT MONO (485 1910);
FORCEPROP 2 LASTPIN (475 1850) $PN 30
J 0
(485 1860);
DISPLAY 0.680851 (485 1860);
PAINT MONO (485 1860);
FORCEPROP 2 LASTPIN (475 1800) $PN 31
J 0
(485 1810);
DISPLAY 0.680851 (485 1810);
PAINT MONO (485 1810);
FORCEPROP 2 LASTPIN (475 1750) $PN 32
J 0
(485 1760);
DISPLAY 0.680851 (485 1760);
PAINT MONO (485 1760);
FORCEPROP 2 LASTPIN (475 1000) $PN 18
J 0
(485 1010);
DISPLAY 0.680851 (485 1010);
PAINT MONO (485 1010);
FORCEPROP 1 LAST MATERIAL IC
J 0
(-320 2282);
DISPLAY 0.723404 (-320 2282);
PAINT GREEN (-320 2282);
FORCEPROP 0 LAST ROOM HSC BOM1
J 0
(-300 2750);
DISPLAY 0.680851 (-300 2750);
FORCEPROP 2 LAST PART_TYPE SMLF
J 0
(-300 2650);
DISPLAY 1.021277 (-300 2650);
FORCEPROP 2 LAST VALUE MP5991GLU-Z
J 0
(-300 2600);
DISPLAY 1.021277 (-300 2600);
FORCEPROP 2 LAST CDS_LIB pure_quanta
J 0
(0 1475);
DISPLAY INVISIBLE (0 1475);
FORCEPROP 1 LAST CDS_LMAN_SYM_OUTLINE -325,775,325,-775
J 0
(0 1475);
DISPLAY 0.468085 (0 1475);
PAINT GREEN (0 1475);
DISPLAY INVISIBLE (0 1475);
FORCEPROP 1 LAST NEEDS_NO_SIZE TRUE
J 0
(0 1475);
DISPLAY 0.723404 (0 1475);
PAINT GREEN (0 1475);
DISPLAY INVISIBLE (0 1475);
FORCEPROP 2 LAST SEC_TYPE 
J 0
(-300 2700);
DISPLAY 1.021277 (-300 2700);
DISPLAY INVISIBLE (-300 2700);
FORCEPROP 1 LAST PATH I35
J 0
(0 1475);
DISPLAY 0.723404 (0 1475);
PAINT GREEN (0 1475);
DISPLAY INVISIBLE (0 1475);
FORCEPROP 1 LAST PART_NUMBER AL005991A00
J 0
(-320 2409);
DISPLAY 0.723404 (-320 2409);
PAINT GREEN (-320 2409);
DISPLAY INVISIBLE (-320 2409);
FORCEADD UNIVERSAL_POWER..1
(-975 2350);
FORCEPROP 3 LASTPIN (-975 2300) SIG_NAME P12V_PSU\g
J 0
(-965 2310);
DISPLAY 0.659574 (-965 2310);
PAINT MONO (-965 2310);
DISPLAY INVISIBLE (-965 2310);
FORCEPROP 1 LAST HDL_POWER P12V_PSU
J 1
(-975 2400);
DISPLAY 0.723404 (-975 2400);
PAINT GREEN (-975 2400);
FORCEPROP 2 LAST CDS_LIB pure_quanta_power
J 0
(-975 2350);
DISPLAY INVISIBLE (-975 2350);
FORCEPROP 2 LAST BOM_COST MIO_VRD_SB
J 0
(-975 2450);
DISPLAY 0.617021 (-975 2450);
PAINT PURPLE (-975 2450);
DISPLAY INVISIBLE (-975 2450);
FORCEPROP 1 LAST PATH I36
J 0
(-925 2375);
DISPLAY 0.872340 (-925 2375);
PAINT AQUA (-925 2375);
DISPLAY INVISIBLE (-925 2375);
FORCEADD UNIVERSAL_GND..1
(975 -2275);
FORCEPROP 3 LASTPIN (975 -2225) SIG_NAME AGND_HSC\g
J 0
(985 -2215);
DISPLAY 0.659574 (985 -2215);
PAINT MONO (985 -2215);
DISPLAY INVISIBLE (985 -2215);
FORCEPROP 1 LAST HDL_POWER AGND_HSC
J 1
(1000 -2350);
DISPLAY 0.723404 (1000 -2350);
PAINT GREEN (1000 -2350);
FORCEPROP 2 LAST CDS_LIB pure_quanta_power
J 0
(975 -2275);
DISPLAY INVISIBLE (975 -2275);
FORCEPROP 1 LAST PATH I37
J 0
(1050 -2275);
DISPLAY 0.872340 (1050 -2275);
PAINT AQUA (1050 -2275);
DISPLAY INVISIBLE (1050 -2275);
FORCEADD Q_CAP..1
(975 -2050);
FORCEPROP 1 LAST LOCATION PC2185
J 0
(1025 -1975);
DISPLAY 0.723404 (1025 -1975);
PAINT AQUA (1025 -1975);
FORCEPROP 0 LAST $SEC 1
J 0
(1025 -1925);
DISPLAY 0.680851 (1025 -1925);
PAINT MONO (1025 -1925);
DISPLAY INVISIBLE (1025 -1925);
FORCEPROP 0 LAST CDS_SEC 1
J 0
(1025 -1925);
DISPLAY 1.021277 (1025 -1925);
DISPLAY INVISIBLE (1025 -1925);
FORCEPROP 1 LASTPIN (975 -1950) $PN 1
J 0
(985 -1970);
DISPLAY 0.787234 (985 -1970);
PAINT MONO (985 -1970);
FORCEPROP 1 LASTPIN (975 -2150) $PN 2
J 0
(985 -2170);
DISPLAY 0.787234 (985 -2170);
PAINT MONO (985 -2170);
FORCEPROP 1 LAST MATERIAL X7R
J 0
(1025 -2125);
DISPLAY 0.723404 (1025 -2125);
PAINT SKYBLUE (1025 -2125);
FORCEPROP 1 LAST PACK_TYPE 0402
J 0
(1025 -2225);
DISPLAY 0.723404 (1025 -2225);
PAINT SKYBLUE (1025 -2225);
FORCEPROP 1 LAST VALUE 0.068UF
J 0
(1025 -2025);
DISPLAY 0.723404 (1025 -2025);
PAINT SKYBLUE (1025 -2025);
FORCEPROP 0 LAST ROOM HSC BOM1
J 0
(1025 -2275);
DISPLAY 0.680851 (1025 -2275);
FORCEPROP 1 LAST VOLTAGE 16V
J 0
(1025 -2075);
DISPLAY 0.723404 (1025 -2075);
PAINT SKYBLUE (1025 -2075);
FORCEPROP 2 LAST CDS_LIB pure_quanta
J 0
(975 -2050);
DISPLAY INVISIBLE (975 -2050);
FORCEPROP 1 LAST TOLERANCE 10%
J 0
(1025 -2100);
DISPLAY 0.978723 (1025 -2100);
PAINT SKYBLUE (1025 -2100);
DISPLAY INVISIBLE (1025 -2100);
FORCEPROP 1 LAST PATH I38
J 0
(1025 -1900);
DISPLAY 0.978723 (1025 -1900);
PAINT WHITE (1025 -1900);
DISPLAY INVISIBLE (1025 -1900);
FORCEPROP 1 LAST PART_NUMBER CH3683K1B09
J 0
(1025 -2175);
DISPLAY 0.723404 (1025 -2175);
PAINT WHITE (1025 -2175);
DISPLAY INVISIBLE (1025 -2175);
FORCEADD Q_RES..1
(1475 -1500);
FORCEPROP 1 LAST LOCATION PR3922
J 0
(1175 -1500);
DISPLAY 0.723404 (1175 -1500);
PAINT AQUA (1175 -1500);
FORCEPROP 0 LAST $SEC 1
J 0
(1625 -1425);
DISPLAY 0.680851 (1625 -1425);
PAINT MONO (1625 -1425);
DISPLAY INVISIBLE (1625 -1425);
FORCEPROP 0 LAST CDS_SEC 1
J 0
(1625 -1425);
DISPLAY 1.021277 (1625 -1425);
DISPLAY INVISIBLE (1625 -1425);
FORCEPROP 1 LASTPIN (1375 -1500) $PN 1
J 0
(1387 -1488);
DISPLAY 0.787234 (1387 -1488);
PAINT MONO (1387 -1488);
FORCEPROP 1 LASTPIN (1575 -1500) $PN 2
J 0
(1537 -1488);
DISPLAY 0.787234 (1537 -1488);
PAINT MONO (1537 -1488);
FORCEPROP 0 LAST ROOM HSC BOM1
J 0
(1750 -1550);
DISPLAY 0.553191 (1750 -1550);
FORCEPROP 1 LAST MATERIAL CHIP
J 0
(1650 -1600);
DISPLAY 0.723404 (1650 -1600);
PAINT SKYBLUE (1650 -1600);
FORCEPROP 1 LAST TOLERANCE 5%
J 0
(1600 -1550);
DISPLAY 0.723404 (1600 -1550);
PAINT SKYBLUE (1600 -1550);
FORCEPROP 1 LAST WATTAGE 1/16W
J 2
(1350 -1600);
DISPLAY 0.723404 (1350 -1600);
PAINT SKYBLUE (1350 -1600);
FORCEPROP 1 LAST VALUE 0
J 2
(1625 -1475);
DISPLAY 0.723404 (1625 -1475);
PAINT SKYBLUE (1625 -1475);
FORCEPROP 1 LAST PACK_TYPE 0402LF
J 0
(1400 -1600);
DISPLAY 0.723404 (1400 -1600);
PAINT SKYBLUE (1400 -1600);
FORCEPROP 2 LAST CDS_LIB pure_quanta
J 0
(1475 -1500);
DISPLAY INVISIBLE (1475 -1500);
FORCEPROP 1 LAST PATH I39
J 0
(1425 -1350);
DISPLAY 0.978723 (1425 -1350);
PAINT WHITE (1425 -1350);
DISPLAY INVISIBLE (1425 -1350);
FORCEPROP 1 LAST PART_NUMBER CS00002JB13
J 0
(1150 -1550);
DISPLAY 0.723404 (1150 -1550);
PAINT WHITE (1150 -1550);
DISPLAY INVISIBLE (1150 -1550);
FORCEADD Q_CAP..1
(-3475 -1425);
FORCEPROP 1 LAST LOCATION PC2181
J 0
(-3400 -1275);
DISPLAY 0.723404 (-3400 -1275);
PAINT AQUA (-3400 -1275);
FORCEPROP 0 LAST $SEC 1
J 0
(-3400 -1225);
DISPLAY 0.680851 (-3400 -1225);
PAINT MONO (-3400 -1225);
DISPLAY INVISIBLE (-3400 -1225);
FORCEPROP 0 LAST CDS_SEC 1
J 0
(-3400 -1225);
DISPLAY 1.021277 (-3400 -1225);
DISPLAY INVISIBLE (-3400 -1225);
FORCEPROP 1 LASTPIN (-3475 -1325) $PN 1
J 0
(-3465 -1345);
DISPLAY 0.787234 (-3465 -1345);
PAINT MONO (-3465 -1345);
FORCEPROP 1 LASTPIN (-3475 -1525) $PN 2
J 0
(-3465 -1545);
DISPLAY 0.787234 (-3465 -1545);
PAINT MONO (-3465 -1545);
FORCEPROP 0 LAST ROOM HSC BOM1
J 0
(-3400 -1225);
DISPLAY 0.680851 (-3400 -1225);
FORCEPROP 1 LAST PACK_TYPE C0402
J 0
(-3400 -1525);
DISPLAY 0.723404 (-3400 -1525);
PAINT SKYBLUE (-3400 -1525);
FORCEPROP 1 LAST MATERIAL X6S
J 0
(-3400 -1425);
DISPLAY 0.723404 (-3400 -1425);
PAINT SKYBLUE (-3400 -1425);
FORCEPROP 1 LAST VOLTAGE 25V
J 0
(-3400 -1375);
DISPLAY 0.723404 (-3400 -1375);
PAINT SKYBLUE (-3400 -1375);
FORCEPROP 1 LAST VALUE 1UF
J 0
(-3400 -1325);
DISPLAY 0.723404 (-3400 -1325);
PAINT SKYBLUE (-3400 -1325);
FORCEPROP 2 LAST CDS_LIB pure_quanta
J 0
(-3475 -1425);
DISPLAY INVISIBLE (-3475 -1425);
FORCEPROP 1 LAST TOLERANCE 10%
J 0
(-3425 -1475);
DISPLAY 0.978723 (-3425 -1475);
PAINT SKYBLUE (-3425 -1475);
DISPLAY INVISIBLE (-3425 -1475);
FORCEPROP 1 LAST PATH I4
J 0
(-3425 -1275);
DISPLAY 0.978723 (-3425 -1275);
PAINT WHITE (-3425 -1275);
DISPLAY INVISIBLE (-3425 -1275);
FORCEPROP 1 LAST PART_NUMBER CH5104KEB02
J 0
(-3400 -1475);
DISPLAY 0.723404 (-3400 -1475);
PAINT WHITE (-3400 -1475);
DISPLAY INVISIBLE (-3400 -1475);
FORCEADD Q_RES..1
(1475 -1325);
FORCEPROP 1 LAST LOCATION PR3921
J 0
(1175 -1325);
DISPLAY 0.723404 (1175 -1325);
PAINT AQUA (1175 -1325);
FORCEPROP 0 LAST $SEC 1
J 0
(1625 -1250);
DISPLAY 0.680851 (1625 -1250);
PAINT MONO (1625 -1250);
DISPLAY INVISIBLE (1625 -1250);
FORCEPROP 0 LAST CDS_SEC 1
J 0
(1625 -1250);
DISPLAY 1.021277 (1625 -1250);
DISPLAY INVISIBLE (1625 -1250);
FORCEPROP 1 LASTPIN (1375 -1325) $PN 1
J 0
(1387 -1313);
DISPLAY 0.787234 (1387 -1313);
PAINT MONO (1387 -1313);
FORCEPROP 1 LASTPIN (1575 -1325) $PN 2
J 0
(1537 -1313);
DISPLAY 0.787234 (1537 -1313);
PAINT MONO (1537 -1313);
FORCEPROP 1 LAST PACK_TYPE 0402LF
J 0
(1400 -1425);
DISPLAY 0.723404 (1400 -1425);
PAINT SKYBLUE (1400 -1425);
FORCEPROP 1 LAST TOLERANCE 5%
J 0
(1600 -1375);
DISPLAY 0.723404 (1600 -1375);
PAINT SKYBLUE (1600 -1375);
FORCEPROP 1 LAST MATERIAL CHIP
J 0
(1650 -1425);
DISPLAY 0.723404 (1650 -1425);
PAINT SKYBLUE (1650 -1425);
FORCEPROP 0 LAST ROOM HSC BOM1
J 0
(1375 -1250);
DISPLAY 0.680851 (1375 -1250);
FORCEPROP 1 LAST VALUE 0
J 2
(1625 -1300);
DISPLAY 0.723404 (1625 -1300);
PAINT SKYBLUE (1625 -1300);
FORCEPROP 1 LAST WATTAGE 1/16W
J 2
(1350 -1425);
DISPLAY 0.723404 (1350 -1425);
PAINT SKYBLUE (1350 -1425);
FORCEPROP 2 LAST CDS_LIB pure_quanta
J 0
(1475 -1325);
DISPLAY INVISIBLE (1475 -1325);
FORCEPROP 1 LAST PATH I40
J 0
(1425 -1175);
DISPLAY 0.978723 (1425 -1175);
PAINT WHITE (1425 -1175);
DISPLAY INVISIBLE (1425 -1175);
FORCEPROP 1 LAST PART_NUMBER CS00002JB13
J 0
(1150 -1375);
DISPLAY 0.723404 (1150 -1375);
PAINT WHITE (1150 -1375);
DISPLAY INVISIBLE (1150 -1375);
FORCEADD UNIVERSAL_POWER..1
(1100 -450);
FORCEPROP 3 LASTPIN (1100 -500) SIG_NAME P12V_AUX\g
J 0
(1110 -490);
DISPLAY 0.659574 (1110 -490);
PAINT MONO (1110 -490);
DISPLAY INVISIBLE (1110 -490);
FORCEPROP 1 LAST HDL_POWER P12V_AUX
J 1
(1100 -400);
DISPLAY 0.723404 (1100 -400);
PAINT GREEN (1100 -400);
FORCEPROP 2 LAST BOM_COST MIO_VRD_SB
J 0
(1100 -350);
DISPLAY 0.617021 (1100 -350);
PAINT PURPLE (1100 -350);
DISPLAY INVISIBLE (1100 -350);
FORCEPROP 2 LAST CDS_LIB pure_quanta_power
J 0
(1100 -450);
DISPLAY INVISIBLE (1100 -450);
FORCEPROP 1 LAST PATH I41
J 0
(1150 -425);
DISPLAY 0.872340 (1150 -425);
PAINT AQUA (1150 -425);
DISPLAY INVISIBLE (1150 -425);
FORCEADD OFFPAGE..4
(2250 -1900);
FORCEPROP 2 LAST $XR2 265 
J 0
(2676 -1900);
DISPLAY 0.638298 (2676 -1900);
PAINT MONO (2676 -1900);
FORCEPROP 2 LAST $XR1 264 
J 0
(2556 -1900);
DISPLAY 0.638298 (2556 -1900);
PAINT MONO (2556 -1900);
FORCEPROP 2 LAST $XR0 263 
J 0
(2436 -1900);
DISPLAY 0.638298 (2436 -1900);
PAINT MONO (2436 -1900);
FORCEPROP 2 LAST CDS_LIB standard
J 0
(2250 -1900);
DISPLAY INVISIBLE (2250 -1900);
FORCEPROP 1 LAST OFFPAGE TRUE
J 0
(2575 -2025);
DISPLAY 0.872340 (2575 -2025);
PAINT GREEN (2575 -2025);
DISPLAY INVISIBLE (2575 -2025);
FORCEPROP 1 LAST COMMENT_BODY TRUE
J 0
(2225 -2000);
DISPLAY 0.872340 (2225 -2000);
PAINT GREEN (2225 -2000);
DISPLAY INVISIBLE (2225 -2000);
FORCEPROP 2 LAST PATH I42
J 0
(2700 -1850);
DISPLAY 1.021277 (2700 -1850);
DISPLAY INVISIBLE (2700 -1850);
FORCEADD OFFPAGE..5
R 2
(2250 -1800);
FORCEPROP 2 LAST $XR2 263 
J 0
(2679 -1800);
DISPLAY 0.638298 (2679 -1800);
PAINT MONO (2679 -1800);
FORCEPROP 2 LAST $XR1 265 
J 0
(2559 -1800);
DISPLAY 0.638298 (2559 -1800);
PAINT MONO (2559 -1800);
FORCEPROP 2 LAST $XR0 264 
J 0
(2439 -1800);
DISPLAY 0.638298 (2439 -1800);
PAINT MONO (2439 -1800);
FORCEPROP 2 LAST CDS_LIB standard
J 2
(2250 -1800);
DISPLAY INVISIBLE (2250 -1800);
FORCEPROP 1 LAST OFFPAGE TRUE
J 2
(1925 -1925);
DISPLAY 0.872340 (1925 -1925);
PAINT AQUA (1925 -1925);
DISPLAY INVISIBLE (1925 -1925);
FORCEPROP 1 LAST COMMENT_BODY TRUE
J 2
(2150 -1875);
DISPLAY 1.170213 (2150 -1875);
PAINT GREEN (2150 -1875);
DISPLAY INVISIBLE (2150 -1875);
FORCEPROP 2 LAST PATH I43
J 0
(2700 -1750);
DISPLAY 1.021277 (2700 -1750);
DISPLAY INVISIBLE (2700 -1750);
FORCEADD OFFPAGE..5
R 2
(2250 -1700);
FORCEPROP 2 LAST $XR2 263 
J 0
(2679 -1700);
DISPLAY 0.638298 (2679 -1700);
PAINT MONO (2679 -1700);
FORCEPROP 2 LAST $XR1 265 
J 0
(2559 -1700);
DISPLAY 0.638298 (2559 -1700);
PAINT MONO (2559 -1700);
FORCEPROP 2 LAST $XR0 264 
J 0
(2439 -1700);
DISPLAY 0.638298 (2439 -1700);
PAINT MONO (2439 -1700);
FORCEPROP 2 LAST CDS_LIB standard
J 2
(2250 -1700);
DISPLAY INVISIBLE (2250 -1700);
FORCEPROP 1 LAST OFFPAGE TRUE
J 2
(1925 -1825);
DISPLAY 0.872340 (1925 -1825);
PAINT AQUA (1925 -1825);
DISPLAY INVISIBLE (1925 -1825);
FORCEPROP 1 LAST COMMENT_BODY TRUE
J 2
(2150 -1775);
DISPLAY 1.170213 (2150 -1775);
PAINT GREEN (2150 -1775);
DISPLAY INVISIBLE (2150 -1775);
FORCEPROP 2 LAST PATH I44
J 0
(2700 -1650);
DISPLAY 1.021277 (2700 -1650);
DISPLAY INVISIBLE (2700 -1650);
FORCEADD OFFPAGE..4
(2250 -1500);
FORCEPROP 2 LAST $XR2 265 
J 0
(2676 -1500);
DISPLAY 0.638298 (2676 -1500);
PAINT MONO (2676 -1500);
FORCEPROP 2 LAST $XR1 264 
J 0
(2556 -1500);
DISPLAY 0.638298 (2556 -1500);
PAINT MONO (2556 -1500);
FORCEPROP 2 LAST $XR0 263 
J 0
(2436 -1500);
DISPLAY 0.638298 (2436 -1500);
PAINT MONO (2436 -1500);
FORCEPROP 2 LAST CDS_LIB standard
J 0
(2250 -1500);
DISPLAY INVISIBLE (2250 -1500);
FORCEPROP 1 LAST OFFPAGE TRUE
J 0
(2575 -1625);
DISPLAY 0.872340 (2575 -1625);
PAINT GREEN (2575 -1625);
DISPLAY INVISIBLE (2575 -1625);
FORCEPROP 1 LAST COMMENT_BODY TRUE
J 0
(2225 -1600);
DISPLAY 0.872340 (2225 -1600);
PAINT GREEN (2225 -1600);
DISPLAY INVISIBLE (2225 -1600);
FORCEPROP 2 LAST PATH I45
J 0
(2700 -1450);
DISPLAY 1.021277 (2700 -1450);
DISPLAY INVISIBLE (2700 -1450);
FORCEADD OFFPAGE..5
R 2
(2250 -1325);
FORCEPROP 2 LAST $XR2 263 
J 0
(2679 -1325);
DISPLAY 0.638298 (2679 -1325);
PAINT MONO (2679 -1325);
FORCEPROP 2 LAST $XR1 265 
J 0
(2559 -1325);
DISPLAY 0.638298 (2559 -1325);
PAINT MONO (2559 -1325);
FORCEPROP 2 LAST $XR0 264 
J 0
(2439 -1325);
DISPLAY 0.638298 (2439 -1325);
PAINT MONO (2439 -1325);
FORCEPROP 2 LAST CDS_LIB standard
J 0
(2250 -1325);
DISPLAY INVISIBLE (2250 -1325);
FORCEPROP 1 LAST OFFPAGE TRUE
J 2
(1925 -1450);
DISPLAY 0.872340 (1925 -1450);
PAINT AQUA (1925 -1450);
DISPLAY INVISIBLE (1925 -1450);
FORCEPROP 1 LAST COMMENT_BODY TRUE
J 2
(2150 -1400);
DISPLAY 1.170213 (2150 -1400);
PAINT GREEN (2150 -1400);
DISPLAY INVISIBLE (2150 -1400);
FORCEPROP 2 LAST PATH I46
J 0
(2700 -1275);
DISPLAY 1.021277 (2700 -1275);
DISPLAY INVISIBLE (2700 -1275);
FORCEADD Q_CAP..1
(975 750);
FORCEPROP 1 LAST LOCATION PC2184
J 0
(1025 825);
DISPLAY 0.723404 (1025 825);
PAINT AQUA (1025 825);
FORCEPROP 0 LAST $SEC 1
J 0
(1025 875);
DISPLAY 0.680851 (1025 875);
PAINT MONO (1025 875);
DISPLAY INVISIBLE (1025 875);
FORCEPROP 0 LAST CDS_SEC 1
J 0
(1025 875);
DISPLAY 1.021277 (1025 875);
DISPLAY INVISIBLE (1025 875);
FORCEPROP 1 LASTPIN (975 850) $PN 1
J 0
(985 830);
DISPLAY 0.787234 (985 830);
PAINT MONO (985 830);
FORCEPROP 1 LASTPIN (975 650) $PN 2
J 0
(985 630);
DISPLAY 0.787234 (985 630);
PAINT MONO (985 630);
FORCEPROP 1 LAST VOLTAGE 16V
J 0
(1025 725);
DISPLAY 0.723404 (1025 725);
PAINT SKYBLUE (1025 725);
FORCEPROP 1 LAST MATERIAL X7R
J 0
(1025 675);
DISPLAY 0.723404 (1025 675);
PAINT SKYBLUE (1025 675);
FORCEPROP 1 LAST PACK_TYPE 0402
J 0
(1025 575);
DISPLAY 0.723404 (1025 575);
PAINT SKYBLUE (1025 575);
FORCEPROP 0 LAST ROOM HSC BOM1
J 0
(1025 525);
DISPLAY 0.680851 (1025 525);
FORCEPROP 1 LAST VALUE 0.068UF
J 0
(1025 775);
DISPLAY 0.723404 (1025 775);
PAINT SKYBLUE (1025 775);
FORCEPROP 2 LAST CDS_LIB pure_quanta
J 0
(975 750);
DISPLAY INVISIBLE (975 750);
FORCEPROP 1 LAST TOLERANCE 10%
J 0
(1025 700);
DISPLAY 0.978723 (1025 700);
PAINT SKYBLUE (1025 700);
DISPLAY INVISIBLE (1025 700);
FORCEPROP 1 LAST PATH I47
J 0
(1025 900);
DISPLAY 0.978723 (1025 900);
PAINT WHITE (1025 900);
DISPLAY INVISIBLE (1025 900);
FORCEPROP 1 LAST PART_NUMBER CH3683K1B09
J 0
(1025 625);
DISPLAY 0.723404 (1025 625);
PAINT WHITE (1025 625);
DISPLAY INVISIBLE (1025 625);
FORCEADD UNIVERSAL_GND..1
(975 525);
FORCEPROP 3 LASTPIN (975 575) SIG_NAME AGND_HSC\g
J 0
(985 585);
DISPLAY 0.659574 (985 585);
PAINT MONO (985 585);
DISPLAY INVISIBLE (985 585);
FORCEPROP 1 LAST HDL_POWER AGND_HSC
J 1
(1000 450);
DISPLAY 0.723404 (1000 450);
PAINT GREEN (1000 450);
FORCEPROP 2 LAST CDS_LIB pure_quanta_power
J 0
(975 525);
DISPLAY INVISIBLE (975 525);
FORCEPROP 1 LAST PATH I48
J 0
(1050 525);
DISPLAY 0.872340 (1050 525);
PAINT AQUA (1050 525);
DISPLAY INVISIBLE (1050 525);
FORCEADD Q_RES..1
(1475 1300);
FORCEPROP 1 LAST LOCATION PR3920
J 0
(1175 1300);
DISPLAY 0.723404 (1175 1300);
PAINT AQUA (1175 1300);
FORCEPROP 0 LAST $SEC 1
J 0
(1625 1375);
DISPLAY 0.680851 (1625 1375);
PAINT MONO (1625 1375);
DISPLAY INVISIBLE (1625 1375);
FORCEPROP 0 LAST CDS_SEC 1
J 0
(1625 1375);
DISPLAY 1.021277 (1625 1375);
DISPLAY INVISIBLE (1625 1375);
FORCEPROP 1 LASTPIN (1375 1300) $PN 1
J 0
(1387 1312);
DISPLAY 0.787234 (1387 1312);
PAINT MONO (1387 1312);
FORCEPROP 1 LASTPIN (1575 1300) $PN 2
J 0
(1537 1312);
DISPLAY 0.787234 (1537 1312);
PAINT MONO (1537 1312);
FORCEPROP 0 LAST ROOM HSC BOM1
J 0
(1375 1150);
DISPLAY 0.680851 (1375 1150);
FORCEPROP 1 LAST PACK_TYPE 0402LF
J 0
(1400 1200);
DISPLAY 0.723404 (1400 1200);
PAINT SKYBLUE (1400 1200);
FORCEPROP 1 LAST WATTAGE 1/16W
J 2
(1350 1200);
DISPLAY 0.723404 (1350 1200);
PAINT SKYBLUE (1350 1200);
FORCEPROP 1 LAST VALUE 0
J 2
(1625 1325);
DISPLAY 0.723404 (1625 1325);
PAINT SKYBLUE (1625 1325);
FORCEPROP 1 LAST TOLERANCE 5%
J 0
(1600 1250);
DISPLAY 0.723404 (1600 1250);
PAINT SKYBLUE (1600 1250);
FORCEPROP 1 LAST MATERIAL CHIP
J 0
(1650 1200);
DISPLAY 0.723404 (1650 1200);
PAINT SKYBLUE (1650 1200);
FORCEPROP 2 LAST CDS_LIB pure_quanta
J 0
(1475 1300);
DISPLAY INVISIBLE (1475 1300);
FORCEPROP 1 LAST PATH I49
J 0
(1425 1450);
DISPLAY 0.978723 (1425 1450);
PAINT WHITE (1425 1450);
DISPLAY INVISIBLE (1425 1450);
FORCEPROP 1 LAST PART_NUMBER CS00002JB13
J 0
(1150 1250);
DISPLAY 0.723404 (1150 1250);
PAINT WHITE (1150 1250);
DISPLAY INVISIBLE (1150 1250);
FORCEADD Q_RES..1
R 1
(-3475 -950);
FORCEPROP 1 LAST LOCATION PR3911
J 0
(-3400 -800);
DISPLAY 0.723404 (-3400 -800);
PAINT AQUA (-3400 -800);
FORCEPROP 0 LAST $SEC 1
R 1
J 0
(-3400 -750);
DISPLAY 0.680851 (-3400 -750);
PAINT MONO (-3400 -750);
DISPLAY INVISIBLE (-3400 -750);
FORCEPROP 0 LAST CDS_SEC 1
R 1
J 0
(-3400 -750);
DISPLAY 1.021277 (-3400 -750);
DISPLAY INVISIBLE (-3400 -750);
FORCEPROP 1 LASTPIN (-3475 -1050) $PN 1
R 1
J 0
(-3487 -1038);
DISPLAY 0.787234 (-3487 -1038);
PAINT MONO (-3487 -1038);
FORCEPROP 1 LASTPIN (-3475 -850) $PN 2
R 1
J 0
(-3487 -888);
DISPLAY 0.787234 (-3487 -888);
PAINT MONO (-3487 -888);
FORCEPROP 1 LAST TOLERANCE 5%
J 0
(-3400 -900);
DISPLAY 0.723404 (-3400 -900);
PAINT SKYBLUE (-3400 -900);
FORCEPROP 1 LAST MATERIAL CHIP
J 0
(-3400 -950);
DISPLAY 0.787234 (-3400 -950);
PAINT SKYBLUE (-3400 -950);
FORCEPROP 1 LAST VALUE 0
R 2
J 0
(-3375 -825);
DISPLAY 0.723404 (-3375 -825);
PAINT SKYBLUE (-3375 -825);
FORCEPROP 1 LAST PACK_TYPE 0402LF
J 0
(-3400 -1100);
DISPLAY 0.723404 (-3400 -1100);
PAINT SKYBLUE (-3400 -1100);
FORCEPROP 1 LAST WATTAGE 1/16W
J 0
(-3400 -1000);
DISPLAY 0.723404 (-3400 -1000);
PAINT SKYBLUE (-3400 -1000);
FORCEPROP 0 LAST ROOM HSC BOM1
J 0
(-3400 -750);
DISPLAY 0.680851 (-3400 -750);
FORCEPROP 2 LAST CDS_LIB pure_quanta
J 0
(-3475 -950);
DISPLAY INVISIBLE (-3475 -950);
FORCEPROP 1 LAST PATH I5
R 1
J 0
(-3625 -1000);
DISPLAY 0.978723 (-3625 -1000);
PAINT WHITE (-3625 -1000);
DISPLAY INVISIBLE (-3625 -1000);
FORCEPROP 1 LAST PART_NUMBER CS00002JB13
J 0
(-3400 -1050);
DISPLAY 0.723404 (-3400 -1050);
PAINT WHITE (-3400 -1050);
DISPLAY INVISIBLE (-3400 -1050);
FORCEADD Q_RES..1
(1475 1475);
FORCEPROP 1 LAST LOCATION PR3919
J 0
(1175 1475);
DISPLAY 0.723404 (1175 1475);
PAINT AQUA (1175 1475);
FORCEPROP 0 LAST $SEC 1
J 0
(1625 1550);
DISPLAY 0.680851 (1625 1550);
PAINT MONO (1625 1550);
DISPLAY INVISIBLE (1625 1550);
FORCEPROP 0 LAST CDS_SEC 1
J 0
(1625 1550);
DISPLAY 1.021277 (1625 1550);
DISPLAY INVISIBLE (1625 1550);
FORCEPROP 1 LASTPIN (1375 1475) $PN 1
J 0
(1387 1487);
DISPLAY 0.787234 (1387 1487);
PAINT MONO (1387 1487);
FORCEPROP 1 LASTPIN (1575 1475) $PN 2
J 0
(1537 1487);
DISPLAY 0.787234 (1537 1487);
PAINT MONO (1537 1487);
FORCEPROP 1 LAST PACK_TYPE 0402LF
J 0
(1400 1375);
DISPLAY 0.723404 (1400 1375);
PAINT SKYBLUE (1400 1375);
FORCEPROP 1 LAST VALUE 0
J 2
(1625 1500);
DISPLAY 0.723404 (1625 1500);
PAINT SKYBLUE (1625 1500);
FORCEPROP 1 LAST WATTAGE 1/16W
J 2
(1350 1375);
DISPLAY 0.723404 (1350 1375);
PAINT SKYBLUE (1350 1375);
FORCEPROP 0 LAST ROOM HSC BOM1
J 0
(1375 1550);
DISPLAY 0.680851 (1375 1550);
FORCEPROP 1 LAST TOLERANCE 5%
J 0
(1600 1425);
DISPLAY 0.723404 (1600 1425);
PAINT SKYBLUE (1600 1425);
FORCEPROP 1 LAST MATERIAL CHIP
J 0
(1650 1375);
DISPLAY 0.723404 (1650 1375);
PAINT SKYBLUE (1650 1375);
FORCEPROP 2 LAST CDS_LIB pure_quanta
J 0
(1475 1475);
DISPLAY INVISIBLE (1475 1475);
FORCEPROP 1 LAST PATH I50
J 0
(1425 1625);
DISPLAY 0.978723 (1425 1625);
PAINT WHITE (1425 1625);
DISPLAY INVISIBLE (1425 1625);
FORCEPROP 1 LAST PART_NUMBER CS00002JB13
J 0
(1150 1425);
DISPLAY 0.723404 (1150 1425);
PAINT WHITE (1150 1425);
DISPLAY INVISIBLE (1150 1425);
FORCEADD UNIVERSAL_POWER..1
(1100 2350);
FORCEPROP 3 LASTPIN (1100 2300) SIG_NAME P12V_AUX\g
J 0
(1110 2310);
DISPLAY 0.659574 (1110 2310);
PAINT MONO (1110 2310);
DISPLAY INVISIBLE (1110 2310);
FORCEPROP 1 LAST HDL_POWER P12V_AUX
J 1
(1100 2400);
DISPLAY 0.723404 (1100 2400);
PAINT GREEN (1100 2400);
FORCEPROP 2 LAST CDS_LIB pure_quanta_power
J 0
(1100 2350);
DISPLAY INVISIBLE (1100 2350);
FORCEPROP 2 LAST BOM_COST MIO_VRD_SB
J 0
(1100 2450);
DISPLAY 0.617021 (1100 2450);
PAINT PURPLE (1100 2450);
DISPLAY INVISIBLE (1100 2450);
FORCEPROP 1 LAST PATH I51
J 0
(1150 2375);
DISPLAY 0.872340 (1150 2375);
PAINT AQUA (1150 2375);
DISPLAY INVISIBLE (1150 2375);
FORCEADD OFFPAGE..4
(2275 900);
FORCEPROP 2 LAST $XR2 265 
J 0
(2701 900);
DISPLAY 0.638298 (2701 900);
PAINT MONO (2701 900);
FORCEPROP 2 LAST $XR1 264 
J 0
(2581 900);
DISPLAY 0.638298 (2581 900);
PAINT MONO (2581 900);
FORCEPROP 2 LAST $XR0 263 
J 0
(2461 900);
DISPLAY 0.638298 (2461 900);
PAINT MONO (2461 900);
FORCEPROP 2 LAST CDS_LIB standard
J 0
(2275 900);
DISPLAY INVISIBLE (2275 900);
FORCEPROP 1 LAST OFFPAGE TRUE
J 0
(2600 775);
DISPLAY 0.872340 (2600 775);
PAINT GREEN (2600 775);
DISPLAY INVISIBLE (2600 775);
FORCEPROP 1 LAST COMMENT_BODY TRUE
J 0
(2250 800);
DISPLAY 0.872340 (2250 800);
PAINT GREEN (2250 800);
DISPLAY INVISIBLE (2250 800);
FORCEPROP 2 LAST PATH I52
J 0
(2725 950);
DISPLAY 1.021277 (2725 950);
DISPLAY INVISIBLE (2725 950);
FORCEADD OFFPAGE..5
R 2
(2275 1000);
FORCEPROP 2 LAST $XR2 263 
J 0
(2704 1000);
DISPLAY 0.638298 (2704 1000);
PAINT MONO (2704 1000);
FORCEPROP 2 LAST $XR1 265 
J 0
(2584 1000);
DISPLAY 0.638298 (2584 1000);
PAINT MONO (2584 1000);
FORCEPROP 2 LAST $XR0 264 
J 0
(2464 1000);
DISPLAY 0.638298 (2464 1000);
PAINT MONO (2464 1000);
FORCEPROP 2 LAST CDS_LIB standard
J 2
(2275 1000);
DISPLAY INVISIBLE (2275 1000);
FORCEPROP 1 LAST OFFPAGE TRUE
J 2
(1950 875);
DISPLAY 0.872340 (1950 875);
PAINT AQUA (1950 875);
DISPLAY INVISIBLE (1950 875);
FORCEPROP 1 LAST COMMENT_BODY TRUE
J 2
(2175 925);
DISPLAY 1.170213 (2175 925);
PAINT GREEN (2175 925);
DISPLAY INVISIBLE (2175 925);
FORCEPROP 2 LAST PATH I53
J 0
(2725 1050);
DISPLAY 1.021277 (2725 1050);
DISPLAY INVISIBLE (2725 1050);
FORCEADD OFFPAGE..5
R 2
(2275 1100);
FORCEPROP 2 LAST $XR2 263 
J 0
(2704 1100);
DISPLAY 0.638298 (2704 1100);
PAINT MONO (2704 1100);
FORCEPROP 2 LAST $XR1 265 
J 0
(2584 1100);
DISPLAY 0.638298 (2584 1100);
PAINT MONO (2584 1100);
FORCEPROP 2 LAST $XR0 264 
J 0
(2464 1100);
DISPLAY 0.638298 (2464 1100);
PAINT MONO (2464 1100);
FORCEPROP 2 LAST CDS_LIB standard
J 2
(2275 1100);
DISPLAY INVISIBLE (2275 1100);
FORCEPROP 1 LAST OFFPAGE TRUE
J 2
(1950 975);
DISPLAY 0.872340 (1950 975);
PAINT AQUA (1950 975);
DISPLAY INVISIBLE (1950 975);
FORCEPROP 1 LAST COMMENT_BODY TRUE
J 2
(2175 1025);
DISPLAY 1.170213 (2175 1025);
PAINT GREEN (2175 1025);
DISPLAY INVISIBLE (2175 1025);
FORCEPROP 2 LAST PATH I54
J 0
(2725 1150);
DISPLAY 1.021277 (2725 1150);
DISPLAY INVISIBLE (2725 1150);
FORCEADD OFFPAGE..4
(2275 1300);
FORCEPROP 2 LAST $XR2 265 
J 0
(2701 1300);
DISPLAY 0.638298 (2701 1300);
PAINT MONO (2701 1300);
FORCEPROP 2 LAST $XR1 264 
J 0
(2581 1300);
DISPLAY 0.638298 (2581 1300);
PAINT MONO (2581 1300);
FORCEPROP 2 LAST $XR0 263 
J 0
(2461 1300);
DISPLAY 0.638298 (2461 1300);
PAINT MONO (2461 1300);
FORCEPROP 2 LAST CDS_LIB standard
J 0
(2275 1300);
DISPLAY INVISIBLE (2275 1300);
FORCEPROP 1 LAST OFFPAGE TRUE
J 0
(2600 1175);
DISPLAY 0.872340 (2600 1175);
PAINT GREEN (2600 1175);
DISPLAY INVISIBLE (2600 1175);
FORCEPROP 1 LAST COMMENT_BODY TRUE
J 0
(2250 1200);
DISPLAY 0.872340 (2250 1200);
PAINT GREEN (2250 1200);
DISPLAY INVISIBLE (2250 1200);
FORCEPROP 2 LAST PATH I55
J 0
(2725 1350);
DISPLAY 1.021277 (2725 1350);
DISPLAY INVISIBLE (2725 1350);
FORCEADD OFFPAGE..5
R 2
(2275 1475);
FORCEPROP 2 LAST $XR2 263 
J 0
(2704 1475);
DISPLAY 0.638298 (2704 1475);
PAINT MONO (2704 1475);
FORCEPROP 2 LAST $XR1 265 
J 0
(2584 1475);
DISPLAY 0.638298 (2584 1475);
PAINT MONO (2584 1475);
FORCEPROP 2 LAST $XR0 264 
J 0
(2464 1475);
DISPLAY 0.638298 (2464 1475);
PAINT MONO (2464 1475);
FORCEPROP 2 LAST CDS_LIB standard
J 0
(2275 1475);
DISPLAY INVISIBLE (2275 1475);
FORCEPROP 1 LAST OFFPAGE TRUE
J 2
(1950 1350);
DISPLAY 0.872340 (1950 1350);
PAINT AQUA (1950 1350);
DISPLAY INVISIBLE (1950 1350);
FORCEPROP 1 LAST COMMENT_BODY TRUE
J 2
(2175 1400);
DISPLAY 1.170213 (2175 1400);
PAINT GREEN (2175 1400);
DISPLAY INVISIBLE (2175 1400);
FORCEPROP 2 LAST PATH I56
J 0
(2725 1525);
DISPLAY 1.021277 (2725 1525);
DISPLAY INVISIBLE (2725 1525);
FORCEADD UNIVERSAL_POWER..1
(-3475 -700);
FORCEPROP 3 LASTPIN (-3475 -750) SIG_NAME HSC_VDD\g
J 0
(-3465 -740);
DISPLAY 0.659574 (-3465 -740);
PAINT MONO (-3465 -740);
DISPLAY INVISIBLE (-3465 -740);
FORCEPROP 1 LAST HDL_POWER HSC_VDD
J 1
(-3475 -650);
DISPLAY 0.723404 (-3475 -650);
PAINT GREEN (-3475 -650);
FORCEPROP 2 LAST CDS_LIB pure_quanta_power
J 0
(-3475 -700);
DISPLAY INVISIBLE (-3475 -700);
FORCEPROP 2 LAST BOM_COST MIO_VRD_SB
J 0
(-3475 -600);
DISPLAY 0.617021 (-3475 -600);
PAINT PURPLE (-3475 -600);
DISPLAY INVISIBLE (-3475 -600);
FORCEPROP 1 LAST PATH I6
J 0
(-3425 -675);
DISPLAY 0.872340 (-3425 -675);
PAINT AQUA (-3425 -675);
DISPLAY INVISIBLE (-3425 -675);
FORCEADD OFFPAGE..4
R 2
(-2775 -1550);
FORCEPROP 2 LAST $XR2 265 
J 0
(-3057 -1586);
DISPLAY 0.638298 (-3057 -1586);
PAINT MONO (-3057 -1586);
FORCEPROP 2 LAST $XR1 264 
J 0
(-3177 -1550);
DISPLAY 0.638298 (-3177 -1550);
PAINT MONO (-3177 -1550);
FORCEPROP 2 LAST $XR0 263 
J 0
(-3057 -1550);
DISPLAY 0.638298 (-3057 -1550);
PAINT MONO (-3057 -1550);
FORCEPROP 2 LAST CDS_LIB standard
J 0
(-2775 -1550);
DISPLAY INVISIBLE (-2775 -1550);
FORCEPROP 1 LAST OFFPAGE TRUE
J 2
(-3100 -1675);
DISPLAY 0.872340 (-3100 -1675);
PAINT GREEN (-3100 -1675);
DISPLAY INVISIBLE (-3100 -1675);
FORCEPROP 1 LAST COMMENT_BODY TRUE
J 2
(-2750 -1650);
DISPLAY 0.872340 (-2750 -1650);
PAINT GREEN (-2750 -1650);
DISPLAY INVISIBLE (-2750 -1650);
FORCEPROP 2 LAST PATH I7
J 0
(-3050 -1500);
DISPLAY 1.021277 (-3050 -1500);
DISPLAY INVISIBLE (-3050 -1500);
FORCEADD UNIVERSAL_GND..1
(-2725 -1350);
FORCEPROP 3 LASTPIN (-2725 -1300) SIG_NAME AGND_HSC\g
J 0
(-2715 -1290);
DISPLAY 0.659574 (-2715 -1290);
PAINT MONO (-2715 -1290);
DISPLAY INVISIBLE (-2715 -1290);
FORCEPROP 1 LAST HDL_POWER AGND_HSC
J 1
(-2700 -1425);
DISPLAY 0.723404 (-2700 -1425);
PAINT GREEN (-2700 -1425);
FORCEPROP 2 LAST CDS_LIB pure_quanta_power
J 0
(-2725 -1350);
DISPLAY INVISIBLE (-2725 -1350);
FORCEPROP 1 LAST PATH I8
J 0
(-2650 -1350);
DISPLAY 0.872340 (-2650 -1350);
PAINT AQUA (-2650 -1350);
DISPLAY INVISIBLE (-2650 -1350);
FORCEADD OFFPAGE..4
R 2
(-2100 -1650);
FORCEPROP 2 LAST $XR2 265 
J 0
(-2622 -1650);
DISPLAY 0.638298 (-2622 -1650);
PAINT MONO (-2622 -1650);
FORCEPROP 2 LAST $XR1 264 
J 0
(-2502 -1650);
DISPLAY 0.638298 (-2502 -1650);
PAINT MONO (-2502 -1650);
FORCEPROP 2 LAST $XR0 263 
J 0
(-2382 -1650);
DISPLAY 0.638298 (-2382 -1650);
PAINT MONO (-2382 -1650);
FORCEPROP 2 LAST CDS_LIB standard
J 0
(-2100 -1650);
DISPLAY INVISIBLE (-2100 -1650);
FORCEPROP 1 LAST OFFPAGE TRUE
J 2
(-2425 -1775);
DISPLAY 0.872340 (-2425 -1775);
PAINT GREEN (-2425 -1775);
DISPLAY INVISIBLE (-2425 -1775);
FORCEPROP 1 LAST COMMENT_BODY TRUE
J 2
(-2075 -1750);
DISPLAY 0.872340 (-2075 -1750);
PAINT GREEN (-2075 -1750);
DISPLAY INVISIBLE (-2075 -1750);
FORCEPROP 2 LAST PATH I9
J 0
(-2375 -1600);
DISPLAY 1.021277 (-2375 -1600);
DISPLAY INVISIBLE (-2375 -1600);
FORCEADD DNS..2
(-1975 725);
PAINT RED (-1975 725);
FORCEPROP 2 LAST CDS_LIB mstr_misc
J 0
(-1975 725);
DISPLAY INVISIBLE (-1975 725);
FORCEPROP 1 LAST COMMENT_BODY TRUE
R 1
J 0
(-1900 500);
DISPLAY 0.872340 (-1900 500);
PAINT GREEN (-1900 500);
DISPLAY INVISIBLE (-1900 500);
FORCEADD DNS..2
(-2650 -2100);
PAINT RED (-2650 -2100);
FORCEPROP 2 LAST CDS_LIB mstr_misc
J 0
(-2650 -2100);
DISPLAY INVISIBLE (-2650 -2100);
FORCEPROP 1 LAST COMMENT_BODY TRUE
R 1
J 0
(-2575 -2325);
DISPLAY 0.872340 (-2575 -2325);
PAINT GREEN (-2575 -2325);
DISPLAY INVISIBLE (-2575 -2325);
FORCEADD QUANTA_TITLE_BLOCK_C..1
(4700 -3250);
FORCEPROP 0 LAST CDS_CON_LAST_MODIFIED Thu Sep 14 16:12:22 2023
J 0
(2815 -3235);
PAINT MONO (2815 -3235);
DISPLAY INVISIBLE (2815 -3235);
FORCEPROP 2 LAST CUSTOM_TXT_CDS <XR_PAGE_TITLE>
J 0
(-3190 2000);
DISPLAY 0.638298 (-3190 2000);
PAINT PINK (-3190 2000);
DISPLAY INVISIBLE (-3190 2000);
FORCEPROP 2 LAST CUSTOM_TXT_CDS <CON_LAST_MODIFIED>
J 0
(2815 -3235);
DISPLAY 0.978723 (2815 -3235);
FORCEPROP 2 LAST CUSTOM_TXT_CDS <Q_NUMBER>
J 0
(3297 -3147);
DISPLAY 1.212766 (3297 -3147);
FORCEPROP 2 LAST CUSTOM_TXT_CDS <Q_PROJ>
J 0
(2318 -3148);
DISPLAY 1.212766 (2318 -3148);
FORCEPROP 2 LAST CUSTOM_TXT_CDS <CON_PAGE_NUM> OF <CON_TOTAL_PAGES>
J 0
(4254 -3232);
DISPLAY 0.978723 (4254 -3232);
FORCEPROP 2 LAST CUSTOM_TXT_CDS <Q_REV>
J 0
(4516 -3147);
DISPLAY 1.212766 (4516 -3147);
FORCEPROP 1 LAST CUSTOM_TXT_CDS <NAME_2>
J 0
(1525 -3200);
FORCEPROP 1 LAST CUSTOM_TXT_CDS <NAME_1>
J 0
(1525 -3075);
FORCEPROP 1 LAST Q_TITLE HSC MP5990 (2/3)
J 0
(-4666 -3224);
DISPLAY 2.446809 (-4666 -3224);
PAINT GREEN (-4666 -3224);
FORCEPROP 1 LAST CDS_LMAN_SYM_OUTLINE -9475,6775,100,-125
J 0
(4700 -3250);
DISPLAY 0.468085 (4700 -3250);
PAINT GREEN (4700 -3250);
DISPLAY INVISIBLE (4700 -3250);
FORCEPROP 2 LAST CDS_LIB pure_quanta
J 0
(4700 -3250);
PAINT MONO (4700 -3250);
DISPLAY INVISIBLE (4700 -3250);
FORCEPROP 2 LAST PAGE_BORDER TRUE
J 0
(-3190 2000);
DISPLAY 0.638298 (-3190 2000);
PAINT PINK (-3190 2000);
DISPLAY INVISIBLE (-3190 2000);
FORCEPROP 2 LAST CDS_XR_PAGE_TITLE CR-264 : @T6G_MB_LIB.T6G(SCH_1):PAGE264
J 0
(-3190 2000);
DISPLAY 0.638298 (-3190 2000);
PAINT PINK (-3190 2000);
DISPLAY INVISIBLE (-3190 2000);
FORCEPROP 1 LAST Q_DEPT BU9
J 1
(937 -3201);
DISPLAY 1.957447 (937 -3201);
PAINT GREEN (937 -3201);
DISPLAY INVISIBLE (937 -3201);
FORCEPROP 1 LAST COMMENT_BODY TRUE
J 0
(4712 -3263);
DISPLAY 0.978723 (4712 -3263);
PAINT GREEN (4712 -3263);
DISPLAY INVISIBLE (4712 -3263);
FORCEADD DNS..2
(-1950 -2075);
PAINT RED (-1950 -2075);
FORCEPROP 2 LAST CDS_LIB mstr_misc
J 0
(-1950 -2075);
DISPLAY INVISIBLE (-1950 -2075);
FORCEPROP 1 LAST COMMENT_BODY TRUE
R 1
J 0
(-1875 -2300);
DISPLAY 0.872340 (-1875 -2300);
PAINT GREEN (-1875 -2300);
DISPLAY INVISIBLE (-1875 -2300);
WIRE 16 -1 (-3450 1275)(-3450 1125);
WIRE 16 -1 (-3450 2050)(-3450 1950);
WIRE 16 -1 (-3475 -1525)(-3475 -1675);
WIRE 16 -1 (975 -2150)(975 -2225);
WIRE 16 -1 (975 650)(975 575);
WIRE 16 -1 (-3475 -750)(-3475 -850);
WIRE 16 -1 (-475 -1750)(-1500 -1750);
FORCEPROP 2 LAST SIG_NAME HSC_CS_2
J 0
(-1010 -1740);
DISPLAY 0.808511 (-1010 -1740);
FORCEPROP 2 LASTPROP $XRERR UNIQUE?
J 0
(-1250 -1740);
DISPLAY 0.638298 (-1250 -1740);
PAINT MONO (-1250 -1740);
DISPLAY INVISIBLE (-1250 -1740);
WIRE 16 -1 (-1500 -1750)(-1500 -1975);
WIRE 16 -1 (-1025 -1850)(-975 -1850);
WIRE 16 -1 (-475 -1850)(-975 -1850);
FORCEPROP 2 LAST SIG_NAME HSC_IMON
J 0
(-1010 -1840);
DISPLAY 0.808511 (-1010 -1840);
WIRE 16 -1 (-975 -1975)(-975 -1850);
WIRE 16 -1 (-1975 -2250)(-1500 -2250);
WIRE 16 -1 (-1975 -2175)(-1975 -2250);
WIRE 16 -1 (-1975 -2250)(-2650 -2250);
WIRE 16 -1 (-975 -2250)(-1500 -2250);
WIRE 16 -1 (-1500 -2175)(-1500 -2250);
WIRE 16 -1 (-975 -2250)(-525 -2250);
WIRE 16 -1 (-975 -2175)(-975 -2250);
WIRE 16 -1 (-2650 -2175)(-2650 -2250);
WIRE 16 -1 (-2650 -2350)(-2650 -2250);
WIRE 16 -1 (-525 -2050)(-525 -2250);
WIRE 16 -1 (-475 -2050)(-525 -2050);
WIRE 16 -1 (600 -950)(600 -1000);
WIRE 16 -1 (600 -900)(600 -950);
WIRE 16 -1 (475 -950)(600 -950);
WIRE 16 -1 (475 -1000)(600 -1000);
WIRE 16 -1 (600 -1000)(600 -1050);
WIRE 16 -1 (600 -1050)(475 -1050);
WIRE 16 -1 (600 -850)(600 -900);
WIRE 16 -1 (475 -900)(600 -900);
WIRE 16 -1 (600 -800)(600 -850);
WIRE 16 -1 (475 -850)(600 -850);
WIRE 16 -1 (600 -750)(600 -800);
WIRE 16 -1 (475 -800)(600 -800);
WIRE 16 -1 (600 -700)(600 -750);
WIRE 16 -1 (475 -750)(600 -750);
WIRE 16 -1 (600 -650)(600 -700);
WIRE 16 -1 (475 -700)(600 -700);
WIRE 16 -1 (600 -600)(600 -650);
WIRE 16 -1 (475 -650)(600 -650);
WIRE 16 -1 (600 -525)(600 -600);
WIRE 16 -1 (475 -600)(600 -600);
WIRE 16 -1 (1100 -525)(600 -525);
WIRE 16 -1 (1100 -500)(1100 -525);
WIRE 16 -1 (475 900)(975 900);
FORCEPROP 2 LAST SIG_NAME HSC_SS
J 0
(590 910);
DISPLAY 0.808511 (590 910);
WIRE 16 -1 (975 900)(2225 900);
WIRE 16 -1 (975 900)(975 850);
WIRE 16 -1 (475 1000)(2225 1000);
FORCEPROP 2 LAST SIG_NAME HSC_VTEMP
J 0
(590 1010);
DISPLAY 0.808511 (590 1010);
WIRE 16 -1 (475 1100)(2225 1100);
FORCEPROP 2 LAST SIG_NAME HSC_FAULT
J 0
(590 1110);
DISPLAY 0.808511 (590 1110);
WIRE 16 -1 (-1825 -1250)(-475 -1250);
FORCEPROP 2 LAST SIG_NAME HSC_MODE_2
J 0
(-1010 -1240);
DISPLAY 0.808511 (-1010 -1240);
FORCEPROP 2 LASTPROP $XRERR UNIQUE?
J 0
(-1250 -1240);
DISPLAY 0.638298 (-1250 -1240);
PAINT MONO (-1250 -1240);
DISPLAY INVISIBLE (-1250 -1240);
WIRE 16 -1 (-475 750)(-525 750);
WIRE 16 -1 (-525 750)(-525 550);
WIRE 16 -1 (-975 550)(-525 550);
WIRE 16 -1 (-975 625)(-975 550);
WIRE 16 -1 (-975 550)(-1500 550);
WIRE 16 -1 (-1500 625)(-1500 550);
WIRE 16 -1 (-2000 550)(-1500 550);
WIRE 16 -1 (-2000 625)(-2000 550);
WIRE 16 -1 (-2000 550)(-2675 550);
WIRE 16 -1 (-2675 625)(-2675 550);
WIRE 16 -1 (-2675 475)(-2675 550);
WIRE 16 -1 (-2100 1150)(-2000 1150);
WIRE 16 -1 (-475 1150)(-2000 1150);
FORCEPROP 2 LAST SIG_NAME HSC_OCREF
J 0
(-1035 1160);
DISPLAY 0.808511 (-1035 1160);
WIRE 16 -1 (-2000 825)(-2000 1150);
WIRE 16 -1 (-475 1250)(-2675 1250);
FORCEPROP 2 LAST SIG_NAME HSC_ON
J 0
(-1035 1260);
DISPLAY 0.808511 (-1035 1260);
WIRE 16 -1 (-2725 1250)(-2675 1250);
WIRE 16 -1 (-2675 1250)(-2675 825);
WIRE 16 -1 (-3450 1750)(-3450 1650);
WIRE 16 -1 (-3450 1650)(-475 1650);
FORCEPROP 2 LAST SIG_NAME HSC_VDD_R_1
J 0
(-1035 1660);
DISPLAY 0.808511 (-1035 1660);
FORCEPROP 2 LASTPROP $XRERR UNIQUE?
J 0
(-1275 1660);
DISPLAY 0.638298 (-1275 1660);
PAINT MONO (-1275 1660);
DISPLAY INVISIBLE (-1275 1660);
WIRE 16 -1 (-3450 1475)(-3450 1650);
WIRE 16 -1 (-475 1450)(-900 1450);
FORCEPROP 2 LAST SIG_NAME HSC_SCREF_1
J 0
(-1035 1460);
DISPLAY 0.808511 (-1035 1460);
FORCEPROP 2 LASTPROP $XRERR UNIQUE?
J 0
(-1275 1460);
DISPLAY 0.638298 (-1275 1460);
PAINT MONO (-1275 1460);
DISPLAY INVISIBLE (-1275 1460);
WIRE 16 -1 (-900 1450)(-900 1375);
WIRE 16 -1 (-900 1375)(-1250 1375);
WIRE 16 -1 (-1825 1550)(-475 1550);
FORCEPROP 2 LAST SIG_NAME HSC_MODE_1
J 0
(-1035 1560);
DISPLAY 0.808511 (-1035 1560);
FORCEPROP 2 LASTPROP $XRERR UNIQUE?
J 0
(-1275 1560);
DISPLAY 0.638298 (-1275 1560);
PAINT MONO (-1275 1560);
DISPLAY INVISIBLE (-1275 1560);
WIRE 16 -1 (975 -1900)(2200 -1900);
WIRE 16 -1 (975 -1900)(975 -1950);
WIRE 16 -1 (475 -1900)(975 -1900);
FORCEPROP 2 LAST SIG_NAME HSC_SS
J 0
(565 -1890);
DISPLAY 0.808511 (565 -1890);
WIRE 16 -1 (475 -1800)(2200 -1800);
FORCEPROP 2 LAST SIG_NAME HSC_VTEMP
J 0
(565 -1790);
DISPLAY 0.808511 (565 -1790);
WIRE 16 -1 (475 -1700)(2200 -1700);
FORCEPROP 2 LAST SIG_NAME HSC_FAULT
J 0
(565 -1690);
DISPLAY 0.808511 (565 -1690);
WIRE 16 -1 (550 -1325)(1375 -1325);
WIRE 16 -1 (550 -1400)(550 -1325);
FORCEPROP 2 LAST SIG_NAME HSC_D_OC_2
J 0
(565 -1315);
DISPLAY 0.808511 (565 -1315);
FORCEPROP 2 LASTPROP $XRERR UNIQUE?
J 0
(325 -1315);
DISPLAY 0.638298 (325 -1315);
PAINT MONO (325 -1315);
DISPLAY INVISIBLE (325 -1315);
WIRE 16 -1 (550 -1400)(475 -1400);
WIRE 16 -1 (-2725 -1250)(-2025 -1250);
WIRE 16 -1 (-2725 -1300)(-2725 -1250);
WIRE 16 -1 (1100 2300)(1100 2275);
WIRE 16 -1 (1100 2275)(600 2275);
WIRE 16 -1 (600 2275)(600 2200);
WIRE 16 -1 (600 2200)(600 2150);
WIRE 16 -1 (475 2200)(600 2200);
WIRE 16 -1 (600 2150)(600 2100);
WIRE 16 -1 (475 2150)(600 2150);
WIRE 16 -1 (600 2100)(600 2050);
WIRE 16 -1 (475 2100)(600 2100);
WIRE 16 -1 (475 2050)(600 2050);
WIRE 16 -1 (600 2050)(600 2000);
WIRE 16 -1 (600 2000)(600 1950);
WIRE 16 -1 (475 2000)(600 2000);
WIRE 16 -1 (600 1950)(600 1900);
WIRE 16 -1 (475 1950)(600 1950);
WIRE 16 -1 (600 1900)(600 1850);
WIRE 16 -1 (475 1900)(600 1900);
WIRE 16 -1 (600 1850)(600 1800);
WIRE 16 -1 (475 1850)(600 1850);
WIRE 16 -1 (600 1800)(600 1750);
WIRE 16 -1 (475 1800)(600 1800);
WIRE 16 -1 (600 1750)(475 1750);
WIRE 16 -1 (-975 2250)(-675 2250);
WIRE 16 -1 (-975 2300)(-975 2250);
WIRE 16 -1 (-675 2250)(-675 2200);
WIRE 16 -1 (-475 2200)(-675 2200);
WIRE 16 -1 (-675 2200)(-675 2150);
WIRE 16 -1 (-475 2150)(-675 2150);
WIRE 16 -1 (-675 2150)(-675 2100);
WIRE 16 -1 (-475 2100)(-675 2100);
WIRE 16 -1 (-675 2100)(-675 2050);
WIRE 16 -1 (-475 2050)(-675 2050);
WIRE 16 -1 (-675 2050)(-675 2000);
WIRE 16 -1 (-475 2000)(-675 2000);
WIRE 16 -1 (-675 2000)(-675 1950);
WIRE 16 -1 (-475 1950)(-675 1950);
WIRE 16 -1 (-675 1950)(-675 1900);
WIRE 16 -1 (-475 1900)(-675 1900);
WIRE 16 -1 (-675 1900)(-675 1850);
WIRE 16 -1 (-475 1850)(-675 1850);
WIRE 16 -1 (-675 1850)(-675 1800);
WIRE 16 -1 (-675 1800)(-475 1800);
WIRE 16 -1 (-2625 1550)(-2025 1550);
WIRE 16 -1 (-2625 1525)(-2625 1550);
WIRE 16 -1 (-975 -500)(-975 -550);
WIRE 16 -1 (-975 -550)(-675 -550);
WIRE 16 -1 (-675 -550)(-675 -600);
WIRE 16 -1 (-475 -600)(-675 -600);
WIRE 16 -1 (-675 -600)(-675 -650);
WIRE 16 -1 (-475 -650)(-675 -650);
WIRE 16 -1 (-675 -650)(-675 -700);
WIRE 16 -1 (-475 -700)(-675 -700);
WIRE 16 -1 (-675 -700)(-675 -750);
WIRE 16 -1 (-475 -750)(-675 -750);
WIRE 16 -1 (-675 -750)(-675 -800);
WIRE 16 -1 (-475 -800)(-675 -800);
WIRE 16 -1 (-675 -800)(-675 -850);
WIRE 16 -1 (-475 -850)(-675 -850);
WIRE 16 -1 (-675 -850)(-675 -900);
WIRE 16 -1 (-475 -900)(-675 -900);
WIRE 16 -1 (-675 -900)(-675 -950);
WIRE 16 -1 (-475 -950)(-675 -950);
WIRE 16 -1 (-675 -950)(-675 -1000);
WIRE 16 -1 (-675 -1000)(-475 -1000);
WIRE 16 -1 (1575 -1500)(2200 -1500);
FORCEPROP 2 LAST SIG_NAME HSC_FLT_TYPE
J 0
(1690 -1490);
DISPLAY 0.808511 (1690 -1490);
WIRE 16 -1 (475 -1500)(1375 -1500);
FORCEPROP 2 LAST SIG_NAME HSC_FLT_TYPE_2
J 0
(565 -1490);
DISPLAY 0.808511 (565 -1490);
FORCEPROP 2 LASTPROP $XRERR UNIQUE?
J 0
(325 -1490);
DISPLAY 0.638298 (325 -1490);
PAINT MONO (325 -1490);
DISPLAY INVISIBLE (325 -1490);
WIRE 16 -1 (-3475 -1325)(-3475 -1150);
WIRE 16 -1 (-3475 -1150)(-475 -1150);
FORCEPROP 2 LAST SIG_NAME HSC_VDD_R_2
J 0
(-1010 -1140);
DISPLAY 0.808511 (-1010 -1140);
FORCEPROP 2 LASTPROP $XRERR UNIQUE?
J 0
(-1250 -1140);
DISPLAY 0.638298 (-1250 -1140);
PAINT MONO (-1250 -1140);
DISPLAY INVISIBLE (-1250 -1140);
WIRE 16 -1 (-3475 -1050)(-3475 -1150);
WIRE 16 -1 (-1975 -1975)(-1975 -1650);
WIRE 16 -1 (-475 -1650)(-1975 -1650);
FORCEPROP 2 LAST SIG_NAME HSC_OCREF
J 0
(-1010 -1640);
DISPLAY 0.808511 (-1010 -1640);
WIRE 16 -1 (-2050 -1650)(-1975 -1650);
WIRE 16 -1 (-475 -1550)(-2650 -1550);
FORCEPROP 2 LAST SIG_NAME HSC_ON
J 0
(-1010 -1540);
DISPLAY 0.808511 (-1010 -1540);
WIRE 16 -1 (-2725 -1550)(-2650 -1550);
WIRE 16 -1 (-2650 -1550)(-2650 -1975);
WIRE 16 -1 (-475 -1350)(-900 -1350);
FORCEPROP 2 LAST SIG_NAME HSC_SCREF_2
J 0
(-1010 -1340);
DISPLAY 0.808511 (-1010 -1340);
FORCEPROP 2 LASTPROP $XRERR UNIQUE?
J 0
(-1250 -1340);
DISPLAY 0.638298 (-1250 -1340);
PAINT MONO (-1250 -1340);
DISPLAY INVISIBLE (-1250 -1340);
WIRE 16 -1 (-900 -1350)(-900 -1425);
WIRE 16 -1 (-900 -1425)(-1225 -1425);
WIRE 16 -1 (-1425 -1425)(-2000 -1425);
FORCEPROP 2 LAST SIG_NAME HSC_SCREF
J 0
(-2010 -1415);
DISPLAY 0.808511 (-2010 -1415);
WIRE 16 -1 (1575 1300)(2225 1300);
FORCEPROP 2 LAST SIG_NAME HSC_FLT_TYPE
J 0
(1715 1310);
DISPLAY 0.808511 (1715 1310);
WIRE 16 -1 (600 1400)(600 1475);
FORCEPROP 2 LAST SIG_NAME HSC_D_OC_1
J 0
(590 1485);
DISPLAY 0.808511 (590 1485);
FORCEPROP 2 LASTPROP $XRERR UNIQUE?
J 0
(350 1485);
DISPLAY 0.638298 (350 1485);
PAINT MONO (350 1485);
DISPLAY INVISIBLE (350 1485);
WIRE 16 -1 (600 1400)(475 1400);
WIRE 16 -1 (600 1475)(1375 1475);
WIRE 16 -1 (1575 1475)(2225 1475);
FORCEPROP 2 LAST SIG_NAME HSC_D_OC_R
J 0
(1790 1485);
DISPLAY 0.808511 (1790 1485);
WIRE 16 -1 (475 1200)(925 1200);
FORCEPROP 2 LAST SIG_NAME HSC_NC1_1
J 0
(590 1210);
DISPLAY 0.808511 (590 1210);
FORCEPROP 2 LASTPROP $XRERR UNIQUE?
J 0
(955 1200);
DISPLAY 0.638298 (955 1200);
PAINT MONO (955 1200);
DISPLAY INVISIBLE (955 1200);
WIRE 16 -1 (475 1300)(1375 1300);
FORCEPROP 2 LAST SIG_NAME HSC_FLT_TYPE_1
J 0
(590 1310);
DISPLAY 0.808511 (590 1310);
FORCEPROP 2 LASTPROP $XRERR UNIQUE?
J 0
(350 1310);
DISPLAY 0.638298 (350 1310);
PAINT MONO (350 1310);
DISPLAY INVISIBLE (350 1310);
WIRE 16 -1 (-475 1050)(-1500 1050);
FORCEPROP 2 LAST SIG_NAME HSC_CS_1
J 0
(-1035 1060);
DISPLAY 0.808511 (-1035 1060);
FORCEPROP 2 LASTPROP $XRERR UNIQUE?
J 0
(-1275 1060);
DISPLAY 0.638298 (-1275 1060);
PAINT MONO (-1275 1060);
DISPLAY INVISIBLE (-1275 1060);
WIRE 16 -1 (-1500 1050)(-1500 825);
WIRE 16 -1 (-975 825)(-975 950);
WIRE 16 -1 (-475 950)(-975 950);
FORCEPROP 2 LAST SIG_NAME HSC_IMON
J 0
(-1035 960);
DISPLAY 0.808511 (-1035 960);
WIRE 16 -1 (-1025 950)(-975 950);
WIRE 16 -1 (-1450 1375)(-2000 1375);
FORCEPROP 2 LAST SIG_NAME HSC_SCREF
J 0
(-2010 1385);
DISPLAY 0.808511 (-2010 1385);
WIRE 16 -1 (1575 -1325)(2200 -1325);
FORCEPROP 2 LAST SIG_NAME HSC_D_OC_R
J 0
(1740 -1315);
DISPLAY 0.808511 (1740 -1315);
WIRE 16 -1 (475 -1600)(925 -1600);
FORCEPROP 2 LAST SIG_NAME HSC_NC1_2
J 0
(590 -1590);
DISPLAY 0.808511 (590 -1590);
FORCEPROP 2 LASTPROP $XRERR UNIQUE?
J 0
(955 -1600);
DISPLAY 0.638298 (955 -1600);
PAINT MONO (955 -1600);
DISPLAY INVISIBLE (955 -1600);
DOT 1 (600 -650);
DOT 1 (-675 2050);
DOT 1 (600 2200);
DOT 1 (600 2150);
DOT 1 (600 2100);
DOT 1 (600 2050);
DOT 1 (600 1950);
DOT 1 (600 1850);
DOT 1 (600 1800);
DOT 1 (975 900);
DOT 1 (600 -700);
DOT 1 (600 -600);
DOT 1 (600 -800);
DOT 1 (600 -750);
DOT 1 (600 -950);
DOT 1 (600 -900);
DOT 1 (600 -1000);
DOT 1 (975 -1900);
DOT 1 (-675 2150);
DOT 1 (-675 2200);
DOT 1 (-675 2000);
DOT 1 (-675 1950);
DOT 1 (-675 1900);
DOT 1 (-675 1850);
DOT 1 (-975 950);
DOT 1 (-975 550);
DOT 1 (-1500 550);
DOT 1 (-2000 1150);
DOT 1 (-2000 550);
DOT 1 (-2675 1250);
DOT 1 (-2675 550);
DOT 1 (-3450 1650);
DOT 1 (-675 -600);
DOT 1 (-675 -700);
DOT 1 (-675 -800);
DOT 1 (-675 -750);
DOT 1 (-675 -900);
DOT 1 (-675 -950);
DOT 1 (-675 -850);
DOT 1 (-1975 -1650);
DOT 1 (-975 -2250);
DOT 1 (-1500 -2250);
DOT 1 (-1975 -2250);
DOT 1 (-2650 -1550);
DOT 1 (-3475 -1150);
DOT 1 (-2650 -2250);
DOT 1 (-675 2100);
DOT 1 (600 2000);
DOT 1 (600 1900);
DOT 1 (-675 -650);
DOT 1 (-975 -1850);
DOT 1 (600 -850);
FORCENOTE
VOUT SLEW RATE: 2V/MS
(1475 -2175) 0;
DISPLAY LEFT (1475 -2175);
DISPLAY 1.021277 (1475 -2175);
FORCENOTE
SOFT START TIME=6MS.
(1475 691) 0;
DISPLAY LEFT (1475 691);
DISPLAY 1.021277 (1475 691);
FORCENOTE
VOUT SLEW RATE: 2V/MS
(1475 625) 0;
DISPLAY LEFT (1475 625);
DISPLAY 1.021277 (1475 625);
FORCENOTE
SOFT START TIME=6MS.
(1475 -2110) 0;
DISPLAY LEFT (1475 -2110);
DISPLAY 1.021277 (1475 -2110);
FORCENOTE
HOT SWAT CIRCUIT
(-4521 3188) 0;
DISPLAY LEFT (-4521 3188);
DISPLAY 2.000000 (-4521 3188);
QUIT
